FILE_TYPE=LIBRARY_PARTS;
primitive 'AST1250','AST1250_BGA';
  pin
    'ADC0_GPIW0':
      PIN_NUMBER='(0,0,0,0,L5,0)';
      INPUT_LOAD='(-0.01,0.01)';
    'ADC10_GPIX2':
      PIN_NUMBER='(0,0,0,0,N5,0)';
      INPUT_LOAD='(-0.01,0.01)';
    'ADC11_GPIX3':
      PIN_NUMBER='(0,0,0,0,N4,0)';
      INPUT_LOAD='(-0.01,0.01)';
    'ADC12_GPIX4':
      PIN_NUMBER='(0,0,0,0,N3,0)';
      OUTPUT_LOAD='(1.0,-1.0)';
    'ADC13_GPIX5':
      PIN_NUMBER='(0,0,0,0,N2,0)';
      OUTPUT_LOAD='(1.0,-1.0)';
    'ADC14_GPIX6':
      PIN_NUMBER='(0,0,0,0,N1,0)';
      INPUT_LOAD='(-0.01,0.01)';
    'ADC15_GPIX7':
      PIN_NUMBER='(0,0,0,0,P5,0)';
      INPUT_LOAD='(-0.01,0.01)';
    'ADC1_GPIW1':
      PIN_NUMBER='(0,0,0,0,L4,0)';
      INPUT_LOAD='(-0.01,0.01)';
    'ADC2_GPIW2':
      PIN_NUMBER='(0,0,0,0,L3,0)';
      INPUT_LOAD='(-0.01,0.01)';
    'ADC3_GPIW3':
      PIN_NUMBER='(0,0,0,0,L2,0)';
      INPUT_LOAD='(-0.01,0.01)';
    'ADC4_GPIW4':
      PIN_NUMBER='(0,0,0,0,L1,0)';
      INPUT_LOAD='(-0.01,0.01)';
    'ADC5_GPIW5':
      PIN_NUMBER='(0,0,0,0,M5,0)';
      INPUT_LOAD='(-0.01,0.01)';
    'ADC6_GPIW6':
      PIN_NUMBER='(0,0,0,0,M4,0)';
      INPUT_LOAD='(-0.01,0.01)';
    'ADC7_GPIW7':
      PIN_NUMBER='(0,0,0,0,M3,0)';
      INPUT_LOAD='(-0.01,0.01)';
    'ADC8_GPIX0':
      PIN_NUMBER='(0,0,0,0,M2,0)';
      INPUT_LOAD='(-0.01,0.01)';
    'ADC9_GPIX1':
      PIN_NUMBER='(0,0,0,0,M1,0)';
      INPUT_LOAD='(-0.01,0.01)';
    'ADCAV33':
      PIN_NUMBER='(0,0,0,0,0,P3)';
      PINUSE='POWER';
      NO_LOAD_CHECK='Both';
      NO_IO_CHECK='Both';
      NO_ASSERT_CHECK='TRUE';
      NO_DIR_CHECK='TRUE';
      ALLOW_CONNECT='TRUE';
    'ADCAVSS':
      PIN_NUMBER='(0,0,0,0,0,P4)';
      PINUSE='GROUND';
      NO_LOAD_CHECK='Both';
      NO_IO_CHECK='Both';
      NO_ASSERT_CHECK='TRUE';
      NO_DIR_CHECK='TRUE';
      ALLOW_CONNECT='TRUE';
    'ADCREXT':
      PIN_NUMBER='(0,0,0,0,P2,0)';
      OUTPUT_LOAD='(1.0,-1.0)';
    'ADCVREFN':
      PIN_NUMBER='(0,0,0,0,K2,0)';
      OUTPUT_LOAD='(1.0,-1.0)';
    'ADCVREFP':
      PIN_NUMBER='(0,0,0,0,K1,0)';
      OUTPUT_LOAD='(1.0,-1.0)';
    'CLKIN':
      PIN_NUMBER='(0,0,AB22,0,0,0)';
      INPUT_LOAD='(-0.01,0.01)';
    'DACAV33':
      PIN_NUMBER='(0,0,0,0,0,P1)';
      PINUSE='POWER';
      NO_LOAD_CHECK='Both';
      NO_IO_CHECK='Both';
      NO_ASSERT_CHECK='TRUE';
      NO_DIR_CHECK='TRUE';
      ALLOW_CONNECT='TRUE';
    'DACAVSS':
      PIN_NUMBER='(0,0,0,0,0,R5)';
      PINUSE='GROUND';
      NO_LOAD_CHECK='Both';
      NO_IO_CHECK='Both';
      NO_ASSERT_CHECK='TRUE';
      NO_DIR_CHECK='TRUE';
      ALLOW_CONNECT='TRUE';
    'DACB':
      PIN_NUMBER='(0,R4,0,0,0,0)';
      OUTPUT_LOAD='(1.0,-1.0)';
    'DACDV33':
      PIN_NUMBER='(0,0,0,0,0,T3)';
      PINUSE='POWER';
      NO_LOAD_CHECK='Both';
      NO_IO_CHECK='Both';
      NO_ASSERT_CHECK='TRUE';
      NO_DIR_CHECK='TRUE';
      ALLOW_CONNECT='TRUE';
    'DACG':
      PIN_NUMBER='(0,R3,0,0,0,0)';
      OUTPUT_LOAD='(1.0,-1.0)';
    'DACR':
      PIN_NUMBER='(0,R2,0,0,0,0)';
      OUTPUT_LOAD='(1.0,-1.0)';
    'DACRSET':
      PIN_NUMBER='(0,R1,0,0,0,0)';
      PIN_TYPE='ANALOG';
      NO_LOAD_CHECK='Both';
      NO_IO_CHECK='Both';
      NO_ASSERT_CHECK='TRUE';
      NO_DIR_CHECK='TRUE';
      ALLOW_CONNECT='TRUE';
    'DDCCLK_GPIOJ6':
      PIN_NUMBER='(0,T2,0,0,0,0)';
      BIDIRECTIONAL='TRUE';
      INPUT_LOAD='(-0.01,0.01)';
      OUTPUT_LOAD='(1.0,-1.0)';
    'DDCDAT_GPIOJ7':
      PIN_NUMBER='(0,T1,0,0,0,0)';
      BIDIRECTIONAL='TRUE';
      INPUT_LOAD='(-0.01,0.01)';
      OUTPUT_LOAD='(1.0,-1.0)';
    'DN_USB11_DN_USB11_HDN2':
      PIN_NUMBER='(0,K3,0,0,0,0)';
      BIDIRECTIONAL='TRUE';
      INPUT_LOAD='(-0.01,0.01)';
      OUTPUT_LOAD='(1.0,-1.0)';
    'DN_USB2_DN_USB2_HDN':
      PIN_NUMBER='(0,AB20,0,0,0,0)';
      BIDIRECTIONAL='TRUE';
      INPUT_LOAD='(-0.01,0.01)';
      OUTPUT_LOAD='(1.0,-1.0)';
    'DP_USB11_DP_USB11_HDP2':
      PIN_NUMBER='(0,K4,0,0,0,0)';
      BIDIRECTIONAL='TRUE';
      INPUT_LOAD='(-0.01,0.01)';
      OUTPUT_LOAD='(1.0,-1.0)';
    'DP_USB2_DP_USB2_HDP':
      PIN_NUMBER='(0,AB21,0,0,0,0)';
      BIDIRECTIONAL='TRUE';
      INPUT_LOAD='(-0.01,0.01)';
      OUTPUT_LOAD='(1.0,-1.0)';
    'ENTEST':
      PIN_NUMBER='(0,0,E4,0,0,0)';
      INPUT_LOAD='(-0.01,0.01)';
    'GND'<35>:
      PIN_NUMBER='(0,0,0,0,0,P9)';
      PINUSE='GROUND';
      NO_LOAD_CHECK='Both';
      NO_IO_CHECK='Both';
      NO_ASSERT_CHECK='TRUE';
      NO_DIR_CHECK='TRUE';
      ALLOW_CONNECT='TRUE';
    'GND'<34>:
      PIN_NUMBER='(0,0,0,0,0,P14)';
      PINUSE='GROUND';
      NO_LOAD_CHECK='Both';
      NO_IO_CHECK='Both';
      NO_ASSERT_CHECK='TRUE';
      NO_DIR_CHECK='TRUE';
      ALLOW_CONNECT='TRUE';
    'GND'<33>:
      PIN_NUMBER='(0,0,0,0,0,P13)';
      PINUSE='GROUND';
      NO_LOAD_CHECK='Both';
      NO_IO_CHECK='Both';
      NO_ASSERT_CHECK='TRUE';
      NO_DIR_CHECK='TRUE';
      ALLOW_CONNECT='TRUE';
    'GND'<32>:
      PIN_NUMBER='(0,0,0,0,0,P12)';
      PINUSE='GROUND';
      NO_LOAD_CHECK='Both';
      NO_IO_CHECK='Both';
      NO_ASSERT_CHECK='TRUE';
      NO_DIR_CHECK='TRUE';
      ALLOW_CONNECT='TRUE';
    'GND'<31>:
      PIN_NUMBER='(0,0,0,0,0,P11)';
      PINUSE='GROUND';
      NO_LOAD_CHECK='Both';
      NO_IO_CHECK='Both';
      NO_ASSERT_CHECK='TRUE';
      NO_DIR_CHECK='TRUE';
      ALLOW_CONNECT='TRUE';
    'GND'<30>:
      PIN_NUMBER='(0,0,0,0,0,P10)';
      PINUSE='GROUND';
      NO_LOAD_CHECK='Both';
      NO_IO_CHECK='Both';
      NO_ASSERT_CHECK='TRUE';
      NO_DIR_CHECK='TRUE';
      ALLOW_CONNECT='TRUE';
    'GND'<29>:
      PIN_NUMBER='(0,0,0,0,0,N9)';
      PINUSE='GROUND';
      NO_LOAD_CHECK='Both';
      NO_IO_CHECK='Both';
      NO_ASSERT_CHECK='TRUE';
      NO_DIR_CHECK='TRUE';
      ALLOW_CONNECT='TRUE';
    'GND'<28>:
      PIN_NUMBER='(0,0,0,0,0,N14)';
      PINUSE='GROUND';
      NO_LOAD_CHECK='Both';
      NO_IO_CHECK='Both';
      NO_ASSERT_CHECK='TRUE';
      NO_DIR_CHECK='TRUE';
      ALLOW_CONNECT='TRUE';
    'GND'<27>:
      PIN_NUMBER='(0,0,0,0,0,N13)';
      PINUSE='GROUND';
      NO_LOAD_CHECK='Both';
      NO_IO_CHECK='Both';
      NO_ASSERT_CHECK='TRUE';
      NO_DIR_CHECK='TRUE';
      ALLOW_CONNECT='TRUE';
    'GND'<26>:
      PIN_NUMBER='(0,0,0,0,0,N12)';
      PINUSE='GROUND';
      NO_LOAD_CHECK='Both';
      NO_IO_CHECK='Both';
      NO_ASSERT_CHECK='TRUE';
      NO_DIR_CHECK='TRUE';
      ALLOW_CONNECT='TRUE';
    'GND'<25>:
      PIN_NUMBER='(0,0,0,0,0,N11)';
      PINUSE='GROUND';
      NO_LOAD_CHECK='Both';
      NO_IO_CHECK='Both';
      NO_ASSERT_CHECK='TRUE';
      NO_DIR_CHECK='TRUE';
      ALLOW_CONNECT='TRUE';
    'GND'<24>:
      PIN_NUMBER='(0,0,0,0,0,N10)';
      PINUSE='GROUND';
      NO_LOAD_CHECK='Both';
      NO_IO_CHECK='Both';
      NO_ASSERT_CHECK='TRUE';
      NO_DIR_CHECK='TRUE';
      ALLOW_CONNECT='TRUE';
    'GND'<23>:
      PIN_NUMBER='(0,0,0,0,0,M9)';
      PINUSE='GROUND';
      NO_LOAD_CHECK='Both';
      NO_IO_CHECK='Both';
      NO_ASSERT_CHECK='TRUE';
      NO_DIR_CHECK='TRUE';
      ALLOW_CONNECT='TRUE';
    'GND'<22>:
      PIN_NUMBER='(0,0,0,0,0,M14)';
      PINUSE='GROUND';
      NO_LOAD_CHECK='Both';
      NO_IO_CHECK='Both';
      NO_ASSERT_CHECK='TRUE';
      NO_DIR_CHECK='TRUE';
      ALLOW_CONNECT='TRUE';
    'GND'<21>:
      PIN_NUMBER='(0,0,0,0,0,M13)';
      PINUSE='GROUND';
      NO_LOAD_CHECK='Both';
      NO_IO_CHECK='Both';
      NO_ASSERT_CHECK='TRUE';
      NO_DIR_CHECK='TRUE';
      ALLOW_CONNECT='TRUE';
    'GND'<20>:
      PIN_NUMBER='(0,0,0,0,0,M12)';
      PINUSE='GROUND';
      NO_LOAD_CHECK='Both';
      NO_IO_CHECK='Both';
      NO_ASSERT_CHECK='TRUE';
      NO_DIR_CHECK='TRUE';
      ALLOW_CONNECT='TRUE';
    'GND'<19>:
      PIN_NUMBER='(0,0,0,0,0,M11)';
      PINUSE='GROUND';
      NO_LOAD_CHECK='Both';
      NO_IO_CHECK='Both';
      NO_ASSERT_CHECK='TRUE';
      NO_DIR_CHECK='TRUE';
      ALLOW_CONNECT='TRUE';
    'GND'<18>:
      PIN_NUMBER='(0,0,0,0,0,M10)';
      PINUSE='GROUND';
      NO_LOAD_CHECK='Both';
      NO_IO_CHECK='Both';
      NO_ASSERT_CHECK='TRUE';
      NO_DIR_CHECK='TRUE';
      ALLOW_CONNECT='TRUE';
    'GND'<17>:
      PIN_NUMBER='(0,0,0,0,0,L9)';
      PINUSE='GROUND';
      NO_LOAD_CHECK='Both';
      NO_IO_CHECK='Both';
      NO_ASSERT_CHECK='TRUE';
      NO_DIR_CHECK='TRUE';
      ALLOW_CONNECT='TRUE';
    'GND'<16>:
      PIN_NUMBER='(0,0,0,0,0,L14)';
      PINUSE='GROUND';
      NO_LOAD_CHECK='Both';
      NO_IO_CHECK='Both';
      NO_ASSERT_CHECK='TRUE';
      NO_DIR_CHECK='TRUE';
      ALLOW_CONNECT='TRUE';
    'GND'<15>:
      PIN_NUMBER='(0,0,0,0,0,L13)';
      PINUSE='GROUND';
      NO_LOAD_CHECK='Both';
      NO_IO_CHECK='Both';
      NO_ASSERT_CHECK='TRUE';
      NO_DIR_CHECK='TRUE';
      ALLOW_CONNECT='TRUE';
    'GND'<14>:
      PIN_NUMBER='(0,0,0,0,0,L12)';
      PINUSE='GROUND';
      NO_LOAD_CHECK='Both';
      NO_IO_CHECK='Both';
      NO_ASSERT_CHECK='TRUE';
      NO_DIR_CHECK='TRUE';
      ALLOW_CONNECT='TRUE';
    'GND'<13>:
      PIN_NUMBER='(0,0,0,0,0,L11)';
      PINUSE='GROUND';
      NO_LOAD_CHECK='Both';
      NO_IO_CHECK='Both';
      NO_ASSERT_CHECK='TRUE';
      NO_DIR_CHECK='TRUE';
      ALLOW_CONNECT='TRUE';
    'GND'<12>:
      PIN_NUMBER='(0,0,0,0,0,L10)';
      PINUSE='GROUND';
      NO_LOAD_CHECK='Both';
      NO_IO_CHECK='Both';
      NO_ASSERT_CHECK='TRUE';
      NO_DIR_CHECK='TRUE';
      ALLOW_CONNECT='TRUE';
    'GND'<11>:
      PIN_NUMBER='(0,0,0,0,0,K9)';
      PINUSE='GROUND';
      NO_LOAD_CHECK='Both';
      NO_IO_CHECK='Both';
      NO_ASSERT_CHECK='TRUE';
      NO_DIR_CHECK='TRUE';
      ALLOW_CONNECT='TRUE';
    'GND'<10>:
      PIN_NUMBER='(0,0,0,0,0,K14)';
      PINUSE='GROUND';
      NO_LOAD_CHECK='Both';
      NO_IO_CHECK='Both';
      NO_ASSERT_CHECK='TRUE';
      NO_DIR_CHECK='TRUE';
      ALLOW_CONNECT='TRUE';
    'GND'<9>:
      PIN_NUMBER='(0,0,0,0,0,K13)';
      PINUSE='GROUND';
      NO_LOAD_CHECK='Both';
      NO_IO_CHECK='Both';
      NO_ASSERT_CHECK='TRUE';
      NO_DIR_CHECK='TRUE';
      ALLOW_CONNECT='TRUE';
    'GND'<8>:
      PIN_NUMBER='(0,0,0,0,0,K12)';
      PINUSE='GROUND';
      NO_LOAD_CHECK='Both';
      NO_IO_CHECK='Both';
      NO_ASSERT_CHECK='TRUE';
      NO_DIR_CHECK='TRUE';
      ALLOW_CONNECT='TRUE';
    'GND'<7>:
      PIN_NUMBER='(0,0,0,0,0,K11)';
      PINUSE='GROUND';
      NO_LOAD_CHECK='Both';
      NO_IO_CHECK='Both';
      NO_ASSERT_CHECK='TRUE';
      NO_DIR_CHECK='TRUE';
      ALLOW_CONNECT='TRUE';
    'GND'<6>:
      PIN_NUMBER='(0,0,0,0,0,K10)';
      PINUSE='GROUND';
      NO_LOAD_CHECK='Both';
      NO_IO_CHECK='Both';
      NO_ASSERT_CHECK='TRUE';
      NO_DIR_CHECK='TRUE';
      ALLOW_CONNECT='TRUE';
    'GND'<5>:
      PIN_NUMBER='(0,0,0,0,0,J9)';
      PINUSE='GROUND';
      NO_LOAD_CHECK='Both';
      NO_IO_CHECK='Both';
      NO_ASSERT_CHECK='TRUE';
      NO_DIR_CHECK='TRUE';
      ALLOW_CONNECT='TRUE';
    'GND'<4>:
      PIN_NUMBER='(0,0,0,0,0,J14)';
      PINUSE='GROUND';
      NO_LOAD_CHECK='Both';
      NO_IO_CHECK='Both';
      NO_ASSERT_CHECK='TRUE';
      NO_DIR_CHECK='TRUE';
      ALLOW_CONNECT='TRUE';
    'GND'<3>:
      PIN_NUMBER='(0,0,0,0,0,J13)';
      PINUSE='GROUND';
      NO_LOAD_CHECK='Both';
      NO_IO_CHECK='Both';
      NO_ASSERT_CHECK='TRUE';
      NO_DIR_CHECK='TRUE';
      ALLOW_CONNECT='TRUE';
    'GND'<2>:
      PIN_NUMBER='(0,0,0,0,0,J12)';
      PINUSE='GROUND';
      NO_LOAD_CHECK='Both';
      NO_IO_CHECK='Both';
      NO_ASSERT_CHECK='TRUE';
      NO_DIR_CHECK='TRUE';
      ALLOW_CONNECT='TRUE';
    'GND'<1>:
      PIN_NUMBER='(0,0,0,0,0,J11)';
      PINUSE='GROUND';
      NO_LOAD_CHECK='Both';
      NO_IO_CHECK='Both';
      NO_ASSERT_CHECK='TRUE';
      NO_DIR_CHECK='TRUE';
      ALLOW_CONNECT='TRUE';
    'GND'<0>:
      PIN_NUMBER='(0,0,0,0,0,J10)';
      PINUSE='GROUND';
      NO_LOAD_CHECK='Both';
      NO_IO_CHECK='Both';
      NO_ASSERT_CHECK='TRUE';
      NO_DIR_CHECK='TRUE';
      ALLOW_CONNECT='TRUE';
    'GPIOA0_MAC1LINK':
      PIN_NUMBER='(0,0,D6,0,0,0)';
      BIDIRECTIONAL='TRUE';
      INPUT_LOAD='(-0.01,0.01)';
      OUTPUT_LOAD='(1.0,-1.0)';
    'GPIOA1_MAC2LINK':
      PIN_NUMBER='(0,0,B5,0,0,0)';
      BIDIRECTIONAL='TRUE';
      INPUT_LOAD='(-0.01,0.01)';
      OUTPUT_LOAD='(1.0,-1.0)';
    'GPIOA2_TIMER3':
      PIN_NUMBER='(0,0,A4,0,0,0)';
      BIDIRECTIONAL='TRUE';
      INPUT_LOAD='(-0.01,0.01)';
      OUTPUT_LOAD='(1.0,-1.0)';
    'GPIOA3_TIMER4':
      PIN_NUMBER='(0,0,E6,0,0,0)';
      BIDIRECTIONAL='TRUE';
      INPUT_LOAD='(-0.01,0.01)';
      OUTPUT_LOAD='(1.0,-1.0)';
    'GPIOA4_TIMER5_SCL9':
      PIN_NUMBER='(0,C5,0,0,0,0)';
      BIDIRECTIONAL='TRUE';
      INPUT_LOAD='(-0.01,0.01)';
      OUTPUT_LOAD='(1.0,-1.0)';
    'GPIOA5_TIMER6_SDA9':
      PIN_NUMBER='(0,B4,0,0,0,0)';
      BIDIRECTIONAL='TRUE';
      INPUT_LOAD='(-0.01,0.01)';
      OUTPUT_LOAD='(1.0,-1.0)';
    'GPIOA6_TIMER7_MDC2':
      PIN_NUMBER='(0,0,0,0,A3,0)';
      BIDIRECTIONAL='TRUE';
      INPUT_LOAD='(-0.01,0.01)';
      OUTPUT_LOAD='(1.0,-1.0)';
    'GPIOA7_TIMER8_MDIO2':
      PIN_NUMBER='(0,0,0,0,D5,0)';
      BIDIRECTIONAL='TRUE';
      INPUT_LOAD='(-0.01,0.01)';
      OUTPUT_LOAD='(1.0,-1.0)';
    'GPIOB0_SALT1':
      PIN_NUMBER='(0,J21,0,0,0,0)';
      BIDIRECTIONAL='TRUE';
      INPUT_LOAD='(-0.01,0.01)';
      OUTPUT_LOAD='(1.0,-1.0)';
    'GPIOB1_SALT2':
      PIN_NUMBER='(0,J20,0,0,0,0)';
      BIDIRECTIONAL='TRUE';
      INPUT_LOAD='(-0.01,0.01)';
      OUTPUT_LOAD='(1.0,-1.0)';
    'GPIOB2_SALT3':
      PIN_NUMBER='(0,H18,0,0,0,0)';
      BIDIRECTIONAL='TRUE';
      INPUT_LOAD='(-0.01,0.01)';
      OUTPUT_LOAD='(1.0,-1.0)';
    'GPIOB3_SALT4':
      PIN_NUMBER='(0,F18,0,0,0,0)';
      BIDIRECTIONAL='TRUE';
      INPUT_LOAD='(-0.01,0.01)';
      OUTPUT_LOAD='(1.0,-1.0)';
    'GPIOB4_LPCRST_N':
      PIN_NUMBER='(0,E19,0,0,0,0)';
      BIDIRECTIONAL='TRUE';
      INPUT_LOAD='(-0.01,0.01)';
      OUTPUT_LOAD='(1.0,-1.0)';
    'GPIOB5_LPCPD_N_LPCSMI_N':
      PIN_NUMBER='(0,H19,0,0,0,0)';
      BIDIRECTIONAL='TRUE';
      INPUT_LOAD='(-0.01,0.01)';
      OUTPUT_LOAD='(1.0,-1.0)';
    'GPIOB6_LPCPME_N':
      PIN_NUMBER='(0,H20,0,0,0,0)';
      BIDIRECTIONAL='TRUE';
      INPUT_LOAD='(-0.01,0.01)';
      OUTPUT_LOAD='(1.0,-1.0)';
    'GPIOB7_EXTRST_N_SPICS1_N':
      PIN_NUMBER='(0,0,E18,0,0,0)';
      BIDIRECTIONAL='TRUE';
      INPUT_LOAD='(-0.01,0.01)';
      OUTPUT_LOAD='(1.0,-1.0)';
    'GPIOC0_SD1CLK_SCL10':
      PIN_NUMBER='(0,0,C4,0,0,0)';
      BIDIRECTIONAL='TRUE';
      INPUT_LOAD='(-0.01,0.01)';
      OUTPUT_LOAD='(1.0,-1.0)';
    'GPIOC1_SD1CMD_SDA10':
      PIN_NUMBER='(0,0,B3,0,0,0)';
      BIDIRECTIONAL='TRUE';
      INPUT_LOAD='(-0.01,0.01)';
      OUTPUT_LOAD='(1.0,-1.0)';
    'GPIOC2_SD1DAT0_SCL11':
      PIN_NUMBER='(0,0,A2,0,0,0)';
      BIDIRECTIONAL='TRUE';
      INPUT_LOAD='(-0.01,0.01)';
      OUTPUT_LOAD='(1.0,-1.0)';
    'GPIOC3_SD1DAT1_SDA11':
      PIN_NUMBER='(0,0,E5,0,0,0)';
      BIDIRECTIONAL='TRUE';
      INPUT_LOAD='(-0.01,0.01)';
      OUTPUT_LOAD='(1.0,-1.0)';
    'GPIOC4_SD1DAT2_SCL12':
      PIN_NUMBER='(0,0,D4,0,0,0)';
      BIDIRECTIONAL='TRUE';
      INPUT_LOAD='(-0.01,0.01)';
      OUTPUT_LOAD='(1.0,-1.0)';
    'GPIOC5_SD1DAT3_SDA12':
      PIN_NUMBER='(0,0,C3,0,0,0)';
      BIDIRECTIONAL='TRUE';
      INPUT_LOAD='(-0.01,0.01)';
      OUTPUT_LOAD='(1.0,-1.0)';
    'GPIOC6_SD1CD_N_SCL13':
      PIN_NUMBER='(0,0,B2,0,0,0)';
      BIDIRECTIONAL='TRUE';
      INPUT_LOAD='(-0.01,0.01)';
      OUTPUT_LOAD='(1.0,-1.0)';
    'GPIOC7_SD1WP_N_SDA13':
      PIN_NUMBER='(0,0,A1,0,0,0)';
      BIDIRECTIONAL='TRUE';
      INPUT_LOAD='(-0.01,0.01)';
      OUTPUT_LOAD='(1.0,-1.0)';
    'GPIOD0_SD2CLK':
      PIN_NUMBER='(0,0,A18,0,0,0)';
      BIDIRECTIONAL='TRUE';
      INPUT_LOAD='(-0.01,0.01)';
      OUTPUT_LOAD='(1.0,-1.0)';
    'GPIOD1_SD2CMD':
      PIN_NUMBER='(0,0,D16,0,0,0)';
      BIDIRECTIONAL='TRUE';
      INPUT_LOAD='(-0.01,0.01)';
      OUTPUT_LOAD='(1.0,-1.0)';
    'GPIOD2_SD2DAT0':
      PIN_NUMBER='(0,0,B17,0,0,0)';
      BIDIRECTIONAL='TRUE';
      INPUT_LOAD='(-0.01,0.01)';
      OUTPUT_LOAD='(1.0,-1.0)';
    'GPIOD3_SD2DAT1':
      PIN_NUMBER='(0,0,A17,0,0,0)';
      BIDIRECTIONAL='TRUE';
      INPUT_LOAD='(-0.01,0.01)';
      OUTPUT_LOAD='(1.0,-1.0)';
    'GPIOD4_SD2DAT2':
      PIN_NUMBER='(0,0,C16,0,0,0)';
      BIDIRECTIONAL='TRUE';
      INPUT_LOAD='(-0.01,0.01)';
      OUTPUT_LOAD='(1.0,-1.0)';
    'GPIOD5_SD2DAT3':
      PIN_NUMBER='(0,0,B16,0,0,0)';
      BIDIRECTIONAL='TRUE';
      INPUT_LOAD='(-0.01,0.01)';
      OUTPUT_LOAD='(1.0,-1.0)';
    'GPIOD6_SD2CD_N':
      PIN_NUMBER='(0,0,A16,0,0,0)';
      BIDIRECTIONAL='TRUE';
      INPUT_LOAD='(-0.01,0.01)';
      OUTPUT_LOAD='(1.0,-1.0)';
    'GPIOD7_SD2WP_N':
      PIN_NUMBER='(0,0,E15,0,0,0)';
      BIDIRECTIONAL='TRUE';
      INPUT_LOAD='(-0.01,0.01)';
      OUTPUT_LOAD='(1.0,-1.0)';
    'GPIOE0_NCTS3':
      PIN_NUMBER='(0,0,D15,0,0,0)';
      BIDIRECTIONAL='TRUE';
      INPUT_LOAD='(-0.01,0.01)';
      OUTPUT_LOAD='(1.0,-1.0)';
    'GPIOE1_NDCD3':
      PIN_NUMBER='(0,0,C15,0,0,0)';
      BIDIRECTIONAL='TRUE';
      INPUT_LOAD='(-0.01,0.01)';
      OUTPUT_LOAD='(1.0,-1.0)';
    'GPIOE2_NDSR3':
      PIN_NUMBER='(0,0,B15,0,0,0)';
      BIDIRECTIONAL='TRUE';
      INPUT_LOAD='(-0.01,0.01)';
      OUTPUT_LOAD='(1.0,-1.0)';
    'GPIOE3_NRI3':
      PIN_NUMBER='(0,0,A15,0,0,0)';
      BIDIRECTIONAL='TRUE';
      INPUT_LOAD='(-0.01,0.01)';
      OUTPUT_LOAD='(1.0,-1.0)';
    'GPIOE4_NDTR3':
      PIN_NUMBER='(0,0,E14,0,0,0)';
      BIDIRECTIONAL='TRUE';
      INPUT_LOAD='(-0.01,0.01)';
      OUTPUT_LOAD='(1.0,-1.0)';
    'GPIOE5_NRTS3':
      PIN_NUMBER='(0,0,D14,0,0,0)';
      BIDIRECTIONAL='TRUE';
      INPUT_LOAD='(-0.01,0.01)';
      OUTPUT_LOAD='(1.0,-1.0)';
    'GPIOE6_TXD3':
      PIN_NUMBER='(0,0,C14,0,0,0)';
      BIDIRECTIONAL='TRUE';
      INPUT_LOAD='(-0.01,0.01)';
      OUTPUT_LOAD='(1.0,-1.0)';
    'GPIOE7_RXD3':
      PIN_NUMBER='(0,0,B14,0,0,0)';
      BIDIRECTIONAL='TRUE';
      INPUT_LOAD='(-0.01,0.01)';
      OUTPUT_LOAD='(1.0,-1.0)';
    'GPIOF0_NCTS4':
      PIN_NUMBER='(0,0,D18,0,0,0)';
      BIDIRECTIONAL='TRUE';
      INPUT_LOAD='(-0.01,0.01)';
      OUTPUT_LOAD='(1.0,-1.0)';
    'GPIOF1_NDCD4_SIOPBI_N':
      PIN_NUMBER='(0,0,B19,0,0,0)';
      BIDIRECTIONAL='TRUE';
      INPUT_LOAD='(-0.01,0.01)';
      OUTPUT_LOAD='(1.0,-1.0)';
    'GPIOF2_NDSR4_SIOPWRGD':
      PIN_NUMBER='(0,0,A20,0,0,0)';
      BIDIRECTIONAL='TRUE';
      INPUT_LOAD='(-0.01,0.01)';
      OUTPUT_LOAD='(1.0,-1.0)';
    'GPIOF3_NRI4_SIOPBO_N':
      PIN_NUMBER='(0,0,D17,0,0,0)';
      BIDIRECTIONAL='TRUE';
      INPUT_LOAD='(-0.01,0.01)';
      OUTPUT_LOAD='(1.0,-1.0)';
    'GPIOF4_NDTR4':
      PIN_NUMBER='(0,0,B18,0,0,0)';
      BIDIRECTIONAL='TRUE';
      INPUT_LOAD='(-0.01,0.01)';
      OUTPUT_LOAD='(1.0,-1.0)';
    'GPIOF5_NRTS4_SIOSCI_N':
      PIN_NUMBER='(0,0,A19,0,0,0)';
      BIDIRECTIONAL='TRUE';
      INPUT_LOAD='(-0.01,0.01)';
      OUTPUT_LOAD='(1.0,-1.0)';
    'GPIOF6_TXD4':
      PIN_NUMBER='(0,0,E16,0,0,0)';
      BIDIRECTIONAL='TRUE';
      INPUT_LOAD='(-0.01,0.01)';
      OUTPUT_LOAD='(1.0,-1.0)';
    'GPIOF7_RXD4':
      PIN_NUMBER='(0,0,C17,0,0,0)';
      BIDIRECTIONAL='TRUE';
      INPUT_LOAD='(-0.01,0.01)';
      OUTPUT_LOAD='(1.0,-1.0)';
    'GPIOG0_SGPSCK':
      PIN_NUMBER='(0,A14,0,0,0,0)';
      BIDIRECTIONAL='TRUE';
      INPUT_LOAD='(-0.01,0.01)';
      OUTPUT_LOAD='(1.0,-1.0)';
    'GPIOG1_SGPSLD':
      PIN_NUMBER='(0,E13,0,0,0,0)';
      BIDIRECTIONAL='TRUE';
      INPUT_LOAD='(-0.01,0.01)';
      OUTPUT_LOAD='(1.0,-1.0)';
    'GPIOG2_SGPSI0':
      PIN_NUMBER='(0,D13,0,0,0,0)';
      BIDIRECTIONAL='TRUE';
      INPUT_LOAD='(-0.01,0.01)';
      OUTPUT_LOAD='(1.0,-1.0)';
    'GPIOG3_SGPSI1':
      PIN_NUMBER='(0,C13,0,0,0,0)';
      BIDIRECTIONAL='TRUE';
      INPUT_LOAD='(-0.01,0.01)';
      OUTPUT_LOAD='(1.0,-1.0)';
    'GPIOG4_WDTRST1_OSCCLK':
      PIN_NUMBER='(0,0,B13,0,0,0)';
      BIDIRECTIONAL='TRUE';
      INPUT_LOAD='(-0.01,0.01)';
      OUTPUT_LOAD='(1.0,-1.0)';
    'GPIOG5_WDTRST2_USBCKI':
      PIN_NUMBER='(0,0,Y21,0,0,0)';
      BIDIRECTIONAL='TRUE';
      INPUT_LOAD='(-0.01,0.01)';
      OUTPUT_LOAD='(1.0,-1.0)';
    'GPIOG6_FLBUSY_N':
      PIN_NUMBER='(0,0,0,AA22,0,0)';
      BIDIRECTIONAL='TRUE';
      INPUT_LOAD='(-0.01,0.01)';
      OUTPUT_LOAD='(1.0,-1.0)';
    'GPIOG7_FLWP_N':
      PIN_NUMBER='(0,0,0,U18,0,0)';
      BIDIRECTIONAL='TRUE';
      INPUT_LOAD='(-0.01,0.01)';
      OUTPUT_LOAD='(1.0,-1.0)';
    'GPIOH0_ROMD8_NCTS6':
      PIN_NUMBER='(0,0,0,A8,0,0)';
      BIDIRECTIONAL='TRUE';
      INPUT_LOAD='(-0.01,0.01)';
      OUTPUT_LOAD='(1.0,-1.0)';
    'GPIOH1_ROMD9_NDCD6':
      PIN_NUMBER='(0,0,0,C7,0,0)';
      BIDIRECTIONAL='TRUE';
      INPUT_LOAD='(-0.01,0.01)';
      OUTPUT_LOAD='(1.0,-1.0)';
    'GPIOH2_ROMD10_NDSR6':
      PIN_NUMBER='(0,0,0,B7,0,0)';
      BIDIRECTIONAL='TRUE';
      INPUT_LOAD='(-0.01,0.01)';
      OUTPUT_LOAD='(1.0,-1.0)';
    'GPIOH3_ROMD11_NRI6':
      PIN_NUMBER='(0,0,0,A7,0,0)';
      BIDIRECTIONAL='TRUE';
      INPUT_LOAD='(-0.01,0.01)';
      OUTPUT_LOAD='(1.0,-1.0)';
    'GPIOH4_ROMD12_NDTR6':
      PIN_NUMBER='(0,0,0,D7,0,0)';
      BIDIRECTIONAL='TRUE';
      INPUT_LOAD='(-0.01,0.01)';
      OUTPUT_LOAD='(1.0,-1.0)';
    'GPIOH5_ROMD13_NRTS6':
      PIN_NUMBER='(0,0,0,B6,0,0)';
      BIDIRECTIONAL='TRUE';
      INPUT_LOAD='(-0.01,0.01)';
      OUTPUT_LOAD='(1.0,-1.0)';
    'GPIOH6_ROMD14_TXD6':
      PIN_NUMBER='(0,0,0,A6,0,0)';
      BIDIRECTIONAL='TRUE';
      INPUT_LOAD='(-0.01,0.01)';
      OUTPUT_LOAD='(1.0,-1.0)';
    'GPIOH7_ROMD15_RXD6':
      PIN_NUMBER='(0,0,0,E7,0,0)';
      BIDIRECTIONAL='TRUE';
      INPUT_LOAD='(-0.01,0.01)';
      OUTPUT_LOAD='(1.0,-1.0)';
    'GPIOI0_SYSCS_N':
      PIN_NUMBER='(0,C22,0,0,0,0)';
      BIDIRECTIONAL='TRUE';
      INPUT_LOAD='(-0.01,0.01)';
      OUTPUT_LOAD='(1.0,-1.0)';
    'GPIOI1_SYSCK':
      PIN_NUMBER='(0,G18,0,0,0,0)';
      BIDIRECTIONAL='TRUE';
      INPUT_LOAD='(-0.01,0.01)';
      OUTPUT_LOAD='(1.0,-1.0)';
    'GPIOI2_SYSDO':
      PIN_NUMBER='(0,D19,0,0,0,0)';
      BIDIRECTIONAL='TRUE';
      INPUT_LOAD='(-0.01,0.01)';
      OUTPUT_LOAD='(1.0,-1.0)';
    'GPIOI3_SYSDI':
      PIN_NUMBER='(0,C20,0,0,0,0)';
      BIDIRECTIONAL='TRUE';
      INPUT_LOAD='(-0.01,0.01)';
      OUTPUT_LOAD='(1.0,-1.0)';
    'GPIOI4_SPICS0_N_VBCS_N':
      PIN_NUMBER='(0,B22,0,0,0,0)';
      BIDIRECTIONAL='TRUE';
      INPUT_LOAD='(-0.01,0.01)';
      OUTPUT_LOAD='(1.0,-1.0)';
    'GPIOI5_SPICK_VBCK':
      PIN_NUMBER='(0,G19,0,0,0,0)';
      BIDIRECTIONAL='TRUE';
      INPUT_LOAD='(-0.01,0.01)';
      OUTPUT_LOAD='(1.0,-1.0)';
    'GPIOI6_SPIDO_VBDO':
      PIN_NUMBER='(0,C18,0,0,0,0)';
      BIDIRECTIONAL='TRUE';
      INPUT_LOAD='(-0.01,0.01)';
      OUTPUT_LOAD='(1.0,-1.0)';
    'GPIOI7_SPIDI_VBDI':
      PIN_NUMBER='(0,E20,0,0,0,0)';
      BIDIRECTIONAL='TRUE';
      INPUT_LOAD='(-0.01,0.01)';
      OUTPUT_LOAD='(1.0,-1.0)';
    'GPIOJ0_SGPMCK':
      PIN_NUMBER='(0,J5,0,0,0,0)';
      BIDIRECTIONAL='TRUE';
      INPUT_LOAD='(-0.01,0.01)';
      OUTPUT_LOAD='(1.0,-1.0)';
    'GPIOJ1_SGPMLD':
      PIN_NUMBER='(0,J4,0,0,0,0)';
      BIDIRECTIONAL='TRUE';
      INPUT_LOAD='(-0.01,0.01)';
      OUTPUT_LOAD='(1.0,-1.0)';
    'GPIOJ2_SGPMO':
      PIN_NUMBER='(0,K5,0,0,0,0)';
      BIDIRECTIONAL='TRUE';
      INPUT_LOAD='(-0.01,0.01)';
      OUTPUT_LOAD='(1.0,-1.0)';
    'GPIOJ3_SGPMI':
      PIN_NUMBER='(0,J3,0,0,0,0)';
      BIDIRECTIONAL='TRUE';
      INPUT_LOAD='(-0.01,0.01)';
      OUTPUT_LOAD='(1.0,-1.0)';
    'GPIOK0_SCL5':
      PIN_NUMBER='(0,E3,0,0,0,0)';
      BIDIRECTIONAL='TRUE';
      INPUT_LOAD='(-0.01,0.01)';
      OUTPUT_LOAD='(1.0,-1.0)';
    'GPIOK1_SDA5':
      PIN_NUMBER='(0,D2,0,0,0,0)';
      BIDIRECTIONAL='TRUE';
      INPUT_LOAD='(-0.01,0.01)';
      OUTPUT_LOAD='(1.0,-1.0)';
    'GPIOK2_SCL6':
      PIN_NUMBER='(0,C1,0,0,0,0)';
      BIDIRECTIONAL='TRUE';
      INPUT_LOAD='(-0.01,0.01)';
      OUTPUT_LOAD='(1.0,-1.0)';
    'GPIOK3_SDA6':
      PIN_NUMBER='(0,F4,0,0,0,0)';
      BIDIRECTIONAL='TRUE';
      INPUT_LOAD='(-0.01,0.01)';
      OUTPUT_LOAD='(1.0,-1.0)';
    'GPIOK4_SCL7':
      PIN_NUMBER='(0,E2,0,0,0,0)';
      BIDIRECTIONAL='TRUE';
      INPUT_LOAD='(-0.01,0.01)';
      OUTPUT_LOAD='(1.0,-1.0)';
    'GPIOK5_SDA7':
      PIN_NUMBER='(0,D1,0,0,0,0)';
      BIDIRECTIONAL='TRUE';
      INPUT_LOAD='(-0.01,0.01)';
      OUTPUT_LOAD='(1.0,-1.0)';
    'GPIOK6_SCL8':
      PIN_NUMBER='(0,G5,0,0,0,0)';
      BIDIRECTIONAL='TRUE';
      INPUT_LOAD='(-0.01,0.01)';
      OUTPUT_LOAD='(1.0,-1.0)';
    'GPIOK7_SDA8':
      PIN_NUMBER='(0,F3,0,0,0,0)';
      BIDIRECTIONAL='TRUE';
      INPUT_LOAD='(-0.01,0.01)';
      OUTPUT_LOAD='(1.0,-1.0)';
    'GPIOL0_NCTS1':
      PIN_NUMBER='(0,0,U1,0,0,0)';
      BIDIRECTIONAL='TRUE';
      INPUT_LOAD='(-0.01,0.01)';
      OUTPUT_LOAD='(1.0,-1.0)';
    'GPIOL1_NDCD1_VPIDE':
      PIN_NUMBER='(0,0,T5,0,0,0)';
      BIDIRECTIONAL='TRUE';
      INPUT_LOAD='(-0.01,0.01)';
      OUTPUT_LOAD='(1.0,-1.0)';
    'GPIOL2_NDSR1_VPIODD':
      PIN_NUMBER='(0,0,U3,0,0,0)';
      BIDIRECTIONAL='TRUE';
      INPUT_LOAD='(-0.01,0.01)';
      OUTPUT_LOAD='(1.0,-1.0)';
    'GPIOL3_NRI1_VPIHS':
      PIN_NUMBER='(0,0,V1,0,0,0)';
      BIDIRECTIONAL='TRUE';
      INPUT_LOAD='(-0.01,0.01)';
      OUTPUT_LOAD='(1.0,-1.0)';
    'GPIOL4_NDTR1_VPIVS':
      PIN_NUMBER='(0,0,U4,0,0,0)';
      BIDIRECTIONAL='TRUE';
      INPUT_LOAD='(-0.01,0.01)';
      OUTPUT_LOAD='(1.0,-1.0)';
    'GPIOL5_NRTS1_VPICLK':
      PIN_NUMBER='(0,0,V2,0,0,0)';
      BIDIRECTIONAL='TRUE';
      INPUT_LOAD='(-0.01,0.01)';
      OUTPUT_LOAD='(1.0,-1.0)';
    'GPIOL6_TXD1_VPIB0':
      PIN_NUMBER='(0,0,W1,0,0,0)';
      BIDIRECTIONAL='TRUE';
      INPUT_LOAD='(-0.01,0.01)';
      OUTPUT_LOAD='(1.0,-1.0)';
    'GPIOL7_RXD1_VPIB1':
      PIN_NUMBER='(0,0,U5,0,0,0)';
      BIDIRECTIONAL='TRUE';
      INPUT_LOAD='(-0.01,0.01)';
      OUTPUT_LOAD='(1.0,-1.0)';
    'GPIOM0_NCTS2_VPIB2':
      PIN_NUMBER='(0,0,V3,0,0,0)';
      BIDIRECTIONAL='TRUE';
      INPUT_LOAD='(-0.01,0.01)';
      OUTPUT_LOAD='(1.0,-1.0)';
    'GPIOM1_NDCD2_VPIB3':
      PIN_NUMBER='(0,0,W2,0,0,0)';
      BIDIRECTIONAL='TRUE';
      INPUT_LOAD='(-0.01,0.01)';
      OUTPUT_LOAD='(1.0,-1.0)';
    'GPIOM2_NDSR2_VPIB4':
      PIN_NUMBER='(0,0,Y1,0,0,0)';
      BIDIRECTIONAL='TRUE';
      INPUT_LOAD='(-0.01,0.01)';
      OUTPUT_LOAD='(1.0,-1.0)';
    'GPIOM3_NRI2_VPIB5':
      PIN_NUMBER='(0,0,V4,0,0,0)';
      BIDIRECTIONAL='TRUE';
      INPUT_LOAD='(-0.01,0.01)';
      OUTPUT_LOAD='(1.0,-1.0)';
    'GPIOM4_NDTR2_VPIB6':
      PIN_NUMBER='(0,0,W3,0,0,0)';
      BIDIRECTIONAL='TRUE';
      INPUT_LOAD='(-0.01,0.01)';
      OUTPUT_LOAD='(1.0,-1.0)';
    'GPIOM5_NRTS2_VPIB7':
      PIN_NUMBER='(0,0,Y2,0,0,0)';
      BIDIRECTIONAL='TRUE';
      INPUT_LOAD='(-0.01,0.01)';
      OUTPUT_LOAD='(1.0,-1.0)';
    'GPIOM6_TXD2_VPIB8':
      PIN_NUMBER='(0,0,AA1,0,0,0)';
      BIDIRECTIONAL='TRUE';
      INPUT_LOAD='(-0.01,0.01)';
      OUTPUT_LOAD='(1.0,-1.0)';
    'GPIOM7_RXD2_VPIB9':
      PIN_NUMBER='(0,0,V5,0,0,0)';
      BIDIRECTIONAL='TRUE';
      INPUT_LOAD='(-0.01,0.01)';
      OUTPUT_LOAD='(1.0,-1.0)';
    'GPION0_PWM0_VPIG0':
      PIN_NUMBER='(0,0,0,0,W4,0)';
      BIDIRECTIONAL='TRUE';
      INPUT_LOAD='(-0.01,0.01)';
      OUTPUT_LOAD='(1.0,-1.0)';
    'GPION1_PWM1_VPIG1':
      PIN_NUMBER='(0,0,0,0,Y3,0)';
      BIDIRECTIONAL='TRUE';
      INPUT_LOAD='(-0.01,0.01)';
      OUTPUT_LOAD='(1.0,-1.0)';
    'GPION2_PWM2_VPIG2':
      PIN_NUMBER='(0,0,0,0,AA2,0)';
      BIDIRECTIONAL='TRUE';
      INPUT_LOAD='(-0.01,0.01)';
      OUTPUT_LOAD='(1.0,-1.0)';
    'GPION3_PWM3_VPIG3':
      PIN_NUMBER='(0,0,0,0,AB1,0)';
      BIDIRECTIONAL='TRUE';
      INPUT_LOAD='(-0.01,0.01)';
      OUTPUT_LOAD='(1.0,-1.0)';
    'GPION4_PWM4_VPIG4':
      PIN_NUMBER='(0,0,0,0,W5,0)';
      BIDIRECTIONAL='TRUE';
      INPUT_LOAD='(-0.01,0.01)';
      OUTPUT_LOAD='(1.0,-1.0)';
    'GPION5_PWM5_VPIG5':
      PIN_NUMBER='(0,0,0,0,Y4,0)';
      BIDIRECTIONAL='TRUE';
      INPUT_LOAD='(-0.01,0.01)';
      OUTPUT_LOAD='(1.0,-1.0)';
    'GPION6_PWM6_VPIG6':
      PIN_NUMBER='(0,0,0,0,AA3,0)';
      BIDIRECTIONAL='TRUE';
      INPUT_LOAD='(-0.01,0.01)';
      OUTPUT_LOAD='(1.0,-1.0)';
    'GPION7_PWM7_VPIG7':
      PIN_NUMBER='(0,0,0,0,AB2,0)';
      BIDIRECTIONAL='TRUE';
      INPUT_LOAD='(-0.01,0.01)';
      OUTPUT_LOAD='(1.0,-1.0)';
    'GPIOO0_TACH0_VPIG8':
      PIN_NUMBER='(0,0,0,0,V6,0)';
      BIDIRECTIONAL='TRUE';
      INPUT_LOAD='(-0.01,0.01)';
      OUTPUT_LOAD='(1.0,-1.0)';
    'GPIOO1_TACH1_VPIG9':
      PIN_NUMBER='(0,0,0,0,Y5,0)';
      BIDIRECTIONAL='TRUE';
      INPUT_LOAD='(-0.01,0.01)';
      OUTPUT_LOAD='(1.0,-1.0)';
    'GPIOO2_TACH2_VPIR0':
      PIN_NUMBER='(0,0,0,0,AA4,0)';
      BIDIRECTIONAL='TRUE';
      INPUT_LOAD='(-0.01,0.01)';
      OUTPUT_LOAD='(1.0,-1.0)';
    'GPIOO3_TACH3_VPIR1':
      PIN_NUMBER='(0,0,0,0,AB3,0)';
      BIDIRECTIONAL='TRUE';
      INPUT_LOAD='(-0.01,0.01)';
      OUTPUT_LOAD='(1.0,-1.0)';
    'GPIOO4_TACH4_VPIR2':
      PIN_NUMBER='(0,0,0,0,W6,0)';
      BIDIRECTIONAL='TRUE';
      INPUT_LOAD='(-0.01,0.01)';
      OUTPUT_LOAD='(1.0,-1.0)';
    'GPIOO5_TACH5_VPIR3':
      PIN_NUMBER='(0,0,0,0,AA5,0)';
      BIDIRECTIONAL='TRUE';
      INPUT_LOAD='(-0.01,0.01)';
      OUTPUT_LOAD='(1.0,-1.0)';
    'GPIOO6_TACH6_VPIR4':
      PIN_NUMBER='(0,0,0,0,AB4,0)';
      BIDIRECTIONAL='TRUE';
      INPUT_LOAD='(-0.01,0.01)';
      OUTPUT_LOAD='(1.0,-1.0)';
    'GPIOO7_TACH7_VPIR5':
      PIN_NUMBER='(0,0,0,0,V7,0)';
      BIDIRECTIONAL='TRUE';
      INPUT_LOAD='(-0.01,0.01)';
      OUTPUT_LOAD='(1.0,-1.0)';
    'GPIOP0_TACH8_VPIR6':
      PIN_NUMBER='(0,0,0,0,Y6,0)';
      BIDIRECTIONAL='TRUE';
      INPUT_LOAD='(-0.01,0.01)';
      OUTPUT_LOAD='(1.0,-1.0)';
    'GPIOP1_TACH9_VPIR7':
      PIN_NUMBER='(0,0,0,0,AB5,0)';
      BIDIRECTIONAL='TRUE';
      INPUT_LOAD='(-0.01,0.01)';
      OUTPUT_LOAD='(1.0,-1.0)';
    'GPIOP2_TACH10_VPIR8':
      PIN_NUMBER='(0,0,0,0,W7,0)';
      BIDIRECTIONAL='TRUE';
      INPUT_LOAD='(-0.01,0.01)';
      OUTPUT_LOAD='(1.0,-1.0)';
    'GPIOP3_TACH11_VPIR9':
      PIN_NUMBER='(0,0,0,0,AA6,0)';
      BIDIRECTIONAL='TRUE';
      INPUT_LOAD='(-0.01,0.01)';
      OUTPUT_LOAD='(1.0,-1.0)';
    'GPIOP4_TACH12':
      PIN_NUMBER='(0,0,0,0,AB6,0)';
      BIDIRECTIONAL='TRUE';
      INPUT_LOAD='(-0.01,0.01)';
      OUTPUT_LOAD='(1.0,-1.0)';
    'GPIOP5_TACH13':
      PIN_NUMBER='(0,0,0,0,Y7,0)';
      BIDIRECTIONAL='TRUE';
      INPUT_LOAD='(-0.01,0.01)';
      OUTPUT_LOAD='(1.0,-1.0)';
    'GPIOP6_TACH14_BMCINT':
      PIN_NUMBER='(0,0,0,0,AA7,0)';
      BIDIRECTIONAL='TRUE';
      INPUT_LOAD='(-0.01,0.01)';
      OUTPUT_LOAD='(1.0,-1.0)';
    'GPIOP7_TACH15_FLACK':
      PIN_NUMBER='(0,0,0,0,AB7,0)';
      BIDIRECTIONAL='TRUE';
      INPUT_LOAD='(-0.01,0.01)';
      OUTPUT_LOAD='(1.0,-1.0)';
    'GPIOQ'<7>:
      PIN_NUMBER='(0,0,H1,0,0,0)';
      BIDIRECTIONAL='TRUE';
      INPUT_LOAD='(-0.01,0.01)';
      OUTPUT_LOAD='(1.0,-1.0)';
    'GPIOQ'<6>:
      PIN_NUMBER='(0,0,H2,0,0,0)';
      BIDIRECTIONAL='TRUE';
      INPUT_LOAD='(-0.01,0.01)';
      OUTPUT_LOAD='(1.0,-1.0)';
    'GPIOQ0_SCL3':
      PIN_NUMBER='(0,D3,0,0,0,0)';
      BIDIRECTIONAL='TRUE';
      INPUT_LOAD='(-0.01,0.01)';
      OUTPUT_LOAD='(1.0,-1.0)';
    'GPIOQ1_SDA3':
      PIN_NUMBER='(0,C2,0,0,0,0)';
      BIDIRECTIONAL='TRUE';
      INPUT_LOAD='(-0.01,0.01)';
      OUTPUT_LOAD='(1.0,-1.0)';
    'GPIOQ2_SCL4':
      PIN_NUMBER='(0,B1,0,0,0,0)';
      BIDIRECTIONAL='TRUE';
      INPUT_LOAD='(-0.01,0.01)';
      OUTPUT_LOAD='(1.0,-1.0)';
    'GPIOQ3_SDA4':
      PIN_NUMBER='(0,F5,0,0,0,0)';
      BIDIRECTIONAL='TRUE';
      INPUT_LOAD='(-0.01,0.01)';
      OUTPUT_LOAD='(1.0,-1.0)';
    'GPIOQ4_SCL14':
      PIN_NUMBER='(0,0,H4,0,0,0)';
      BIDIRECTIONAL='TRUE';
      INPUT_LOAD='(-0.01,0.01)';
      OUTPUT_LOAD='(1.0,-1.0)';
    'GPIOQ5_SDA14':
      PIN_NUMBER='(0,0,H3,0,0,0)';
      BIDIRECTIONAL='TRUE';
      INPUT_LOAD='(-0.01,0.01)';
      OUTPUT_LOAD='(1.0,-1.0)';
    'GPIOR0_ROMCS1_N':
      PIN_NUMBER='(0,0,0,V20,0,0)';
      BIDIRECTIONAL='TRUE';
      INPUT_LOAD='(-0.01,0.01)';
      OUTPUT_LOAD='(1.0,-1.0)';
    'GPIOR1_ROMCS2_N':
      PIN_NUMBER='(0,0,0,W21,0,0)';
      BIDIRECTIONAL='TRUE';
      INPUT_LOAD='(-0.01,0.01)';
      OUTPUT_LOAD='(1.0,-1.0)';
    'GPIOR2_ROMCS3_N':
      PIN_NUMBER='(0,0,0,Y22,0,0)';
      BIDIRECTIONAL='TRUE';
      INPUT_LOAD='(-0.01,0.01)';
      OUTPUT_LOAD='(1.0,-1.0)';
    'GPIOR3_ROMCS4_N':
      PIN_NUMBER='(0,0,0,U19,0,0)';
      BIDIRECTIONAL='TRUE';
      INPUT_LOAD='(-0.01,0.01)';
      OUTPUT_LOAD='(1.0,-1.0)';
    'GPIOR4_ROMA24_VPOR6':
      PIN_NUMBER='(0,0,0,V21,0,0)';
      BIDIRECTIONAL='TRUE';
      INPUT_LOAD='(-0.01,0.01)';
      OUTPUT_LOAD='(1.0,-1.0)';
    'GPIOR5_ROMA25_VPOR7':
      PIN_NUMBER='(0,0,0,W22,0,0)';
      BIDIRECTIONAL='TRUE';
      INPUT_LOAD='(-0.01,0.01)';
      OUTPUT_LOAD='(1.0,-1.0)';
    'GPIOR6_MDC1':
      PIN_NUMBER='(0,0,0,C6,0,0)';
      BIDIRECTIONAL='TRUE';
      INPUT_LOAD='(-0.01,0.01)';
      OUTPUT_LOAD='(1.0,-1.0)';
    'GPIOR7_MDIO1':
      PIN_NUMBER='(0,0,0,A5,0,0)';
      BIDIRECTIONAL='TRUE';
      INPUT_LOAD='(-0.01,0.01)';
      OUTPUT_LOAD='(1.0,-1.0)';
    'GPIOY0_SIOS3_N':
      PIN_NUMBER='(0,0,0,0,0,C21)';
      PINUSE='NC';
      NO_LOAD_CHECK='Both';
      NO_IO_CHECK='Both';
      NO_ASSERT_CHECK='TRUE';
      NO_DIR_CHECK='TRUE';
      ALLOW_CONNECT='TRUE';
    'GPIOY1_SIOS5_N':
      PIN_NUMBER='(0,0,0,0,0,F20)';
      PINUSE='NC';
      NO_LOAD_CHECK='Both';
      NO_IO_CHECK='Both';
      NO_ASSERT_CHECK='TRUE';
      NO_DIR_CHECK='TRUE';
      ALLOW_CONNECT='TRUE';
    'GPIOY2_SIOPWREQ_N':
      PIN_NUMBER='(0,0,0,0,0,G20)';
      PINUSE='NC';
      NO_LOAD_CHECK='Both';
      NO_IO_CHECK='Both';
      NO_ASSERT_CHECK='TRUE';
      NO_DIR_CHECK='TRUE';
      ALLOW_CONNECT='TRUE';
    'GPIOY3_SIOONCTRL_N':
      PIN_NUMBER='(0,0,K20,0,0,0)';
      INPUT_LOAD='(-0.01,0.01)';
    'HPLLAV33':
      PIN_NUMBER='(0,0,0,0,0,V17)';
      PINUSE='POWER';
      NO_LOAD_CHECK='Both';
      NO_IO_CHECK='Both';
      NO_ASSERT_CHECK='TRUE';
      NO_DIR_CHECK='TRUE';
      ALLOW_CONNECT='TRUE';
    'IV12D'<10>:
      PIN_NUMBER='(0,0,0,0,0,U13)';
      PINUSE='POWER';
      NO_LOAD_CHECK='Both';
      NO_IO_CHECK='Both';
      NO_ASSERT_CHECK='TRUE';
      NO_DIR_CHECK='TRUE';
      ALLOW_CONNECT='TRUE';
    'IV12D'<9>:
      PIN_NUMBER='(0,0,0,0,0,U12)';
      PINUSE='POWER';
      NO_LOAD_CHECK='Both';
      NO_IO_CHECK='Both';
      NO_ASSERT_CHECK='TRUE';
      NO_DIR_CHECK='TRUE';
      ALLOW_CONNECT='TRUE';
    'IV12D'<8>:
      PIN_NUMBER='(0,0,0,0,0,R17)';
      PINUSE='POWER';
      NO_LOAD_CHECK='Both';
      NO_IO_CHECK='Both';
      NO_ASSERT_CHECK='TRUE';
      NO_DIR_CHECK='TRUE';
      ALLOW_CONNECT='TRUE';
    'IV12D'<7>:
      PIN_NUMBER='(0,0,0,0,0,R6)';
      PINUSE='POWER';
      NO_LOAD_CHECK='Both';
      NO_IO_CHECK='Both';
      NO_ASSERT_CHECK='TRUE';
      NO_DIR_CHECK='TRUE';
      ALLOW_CONNECT='TRUE';
    'IV12D'<6>:
      PIN_NUMBER='(0,0,0,0,0,P17)';
      PINUSE='POWER';
      NO_LOAD_CHECK='Both';
      NO_IO_CHECK='Both';
      NO_ASSERT_CHECK='TRUE';
      NO_DIR_CHECK='TRUE';
      ALLOW_CONNECT='TRUE';
    'IV12D'<5>:
      PIN_NUMBER='(0,0,0,0,0,P6)';
      PINUSE='POWER';
      NO_LOAD_CHECK='Both';
      NO_IO_CHECK='Both';
      NO_ASSERT_CHECK='TRUE';
      NO_DIR_CHECK='TRUE';
      ALLOW_CONNECT='TRUE';
    'IV12D'<4>:
      PIN_NUMBER='(0,0,0,0,0,L17)';
      PINUSE='POWER';
      NO_LOAD_CHECK='Both';
      NO_IO_CHECK='Both';
      NO_ASSERT_CHECK='TRUE';
      NO_DIR_CHECK='TRUE';
      ALLOW_CONNECT='TRUE';
    'IV12D'<3>:
      PIN_NUMBER='(0,0,0,0,0,L6)';
      PINUSE='POWER';
      NO_LOAD_CHECK='Both';
      NO_IO_CHECK='Both';
      NO_ASSERT_CHECK='TRUE';
      NO_DIR_CHECK='TRUE';
      ALLOW_CONNECT='TRUE';
    'IV12D'<2>:
      PIN_NUMBER='(0,0,0,0,0,K6)';
      PINUSE='POWER';
      NO_LOAD_CHECK='Both';
      NO_IO_CHECK='Both';
      NO_ASSERT_CHECK='TRUE';
      NO_DIR_CHECK='TRUE';
      ALLOW_CONNECT='TRUE';
    'IV12D'<1>:
      PIN_NUMBER='(0,0,0,0,0,F15)';
      PINUSE='POWER';
      NO_LOAD_CHECK='Both';
      NO_IO_CHECK='Both';
      NO_ASSERT_CHECK='TRUE';
      NO_DIR_CHECK='TRUE';
      ALLOW_CONNECT='TRUE';
    'IV12D'<0>:
      PIN_NUMBER='(0,0,0,0,0,F14)';
      PINUSE='POWER';
      NO_LOAD_CHECK='Both';
      NO_IO_CHECK='Both';
      NO_ASSERT_CHECK='TRUE';
      NO_DIR_CHECK='TRUE';
      ALLOW_CONNECT='TRUE';
    'LAD'<3>:
      PIN_NUMBER='(0,C19,0,0,0,0)';
      BIDIRECTIONAL='TRUE';
      INPUT_LOAD='(-0.01,0.01)';
      OUTPUT_LOAD='(1.0,-1.0)';
    'LAD'<2>:
      PIN_NUMBER='(0,F19,0,0,0,0)';
      BIDIRECTIONAL='TRUE';
      INPUT_LOAD='(-0.01,0.01)';
      OUTPUT_LOAD='(1.0,-1.0)';
    'LAD'<1>:
      PIN_NUMBER='(0,A22,0,0,0,0)';
      BIDIRECTIONAL='TRUE';
      INPUT_LOAD='(-0.01,0.01)';
      OUTPUT_LOAD='(1.0,-1.0)';
    'LAD'<0>:
      PIN_NUMBER='(0,B21,0,0,0,0)';
      BIDIRECTIONAL='TRUE';
      INPUT_LOAD='(-0.01,0.01)';
      OUTPUT_LOAD='(1.0,-1.0)';
    'LCLK':
      PIN_NUMBER='(0,B20,0,0,0,0)';
      BIDIRECTIONAL='TRUE';
      INPUT_LOAD='(-0.01,0.01)';
      OUTPUT_LOAD='(1.0,-1.0)';
    'LFRAME_N':
      PIN_NUMBER='(0,A21,0,0,0,0)';
      BIDIRECTIONAL='TRUE';
      INPUT_LOAD='(-0.01,0.01)';
      OUTPUT_LOAD='(1.0,-1.0)';
    'LSIRQ_N':
      PIN_NUMBER='(0,E17,0,0,0,0)';
      BIDIRECTIONAL='TRUE';
      INPUT_LOAD='(-0.01,0.01)';
      OUTPUT_LOAD='(1.0,-1.0)';
    'MA'<14>:
      PIN_NUMBER='(AB17,0,0,0,0,0)';
      OUTPUT_LOAD='(1.0,-1.0)';
    'MA'<13>:
      PIN_NUMBER='(Y17,0,0,0,0,0)';
      OUTPUT_LOAD='(1.0,-1.0)';
    'MA'<12>:
      PIN_NUMBER='(W17,0,0,0,0,0)';
      OUTPUT_LOAD='(1.0,-1.0)';
    'MA'<11>:
      PIN_NUMBER='(AA16,0,0,0,0,0)';
      OUTPUT_LOAD='(1.0,-1.0)';
    'MA'<10>:
      PIN_NUMBER='(Y15,0,0,0,0,0)';
      OUTPUT_LOAD='(1.0,-1.0)';
    'MA'<9>:
      PIN_NUMBER='(AA17,0,0,0,0,0)';
      OUTPUT_LOAD='(1.0,-1.0)';
    'MA'<8>:
      PIN_NUMBER='(AB16,0,0,0,0,0)';
      OUTPUT_LOAD='(1.0,-1.0)';
    'MA'<7>:
      PIN_NUMBER='(AB18,0,0,0,0,0)';
      OUTPUT_LOAD='(1.0,-1.0)';
    'MA'<6>:
      PIN_NUMBER='(AA15,0,0,0,0,0)';
      OUTPUT_LOAD='(1.0,-1.0)';
    'MA'<5>:
      PIN_NUMBER='(W16,0,0,0,0,0)';
      OUTPUT_LOAD='(1.0,-1.0)';
    'MA'<4>:
      PIN_NUMBER='(AB15,0,0,0,0,0)';
      OUTPUT_LOAD='(1.0,-1.0)';
    'MA'<3>:
      PIN_NUMBER='(Y16,0,0,0,0,0)';
      OUTPUT_LOAD='(1.0,-1.0)';
    'MA'<2>:
      PIN_NUMBER='(V15,0,0,0,0,0)';
      OUTPUT_LOAD='(1.0,-1.0)';
    'MA'<1>:
      PIN_NUMBER='(W15,0,0,0,0,0)';
      OUTPUT_LOAD='(1.0,-1.0)';
    'MA'<0>:
      PIN_NUMBER='(AB14,0,0,0,0,0)';
      OUTPUT_LOAD='(1.0,-1.0)';
    'MBA'<2>:
      PIN_NUMBER='(Y14,0,0,0,0,0)';
      OUTPUT_LOAD='(1.0,-1.0)';
    'MBA'<1>:
      PIN_NUMBER='(AA14,0,0,0,0,0)';
      OUTPUT_LOAD='(1.0,-1.0)';
    'MBA'<0>:
      PIN_NUMBER='(W14,0,0,0,0,0)';
      OUTPUT_LOAD='(1.0,-1.0)';
    'MCAS_N':
      PIN_NUMBER='(AB13,0,0,0,0,0)';
      OUTPUT_LOAD='(1.0,-1.0)';
    'MCKP':
      PIN_NUMBER='(AB12,0,0,0,0,0)';
      OUTPUT_LOAD='(1.0,-1.0)';
    'MCKE':
      PIN_NUMBER='(Y12,0,0,0,0,0)';
      OUTPUT_LOAD='(1.0,-1.0)';
    'MCKN':
      PIN_NUMBER='(AA12,0,0,0,0,0)';
      OUTPUT_LOAD='(1.0,-1.0)';
    'MCS_N':
      PIN_NUMBER='(AA13,0,0,0,0,0)';
      OUTPUT_LOAD='(1.0,-1.0)';
    'MDM'<1>:
      PIN_NUMBER='(V8,0,0,0,0,0)';
      OUTPUT_LOAD='(1.0,-1.0)';
    'MDM'<0>:
      PIN_NUMBER='(W10,0,0,0,0,0)';
      OUTPUT_LOAD='(1.0,-1.0)';
    'MDQ'<15>:
      PIN_NUMBER='(W8,0,0,0,0,0)';
      BIDIRECTIONAL='TRUE';
      INPUT_LOAD='(-0.01,0.01)';
      OUTPUT_LOAD='(1.0,-1.0)';
    'MDQ'<14>:
      PIN_NUMBER='(Y8,0,0,0,0,0)';
      BIDIRECTIONAL='TRUE';
      INPUT_LOAD='(-0.01,0.01)';
      OUTPUT_LOAD='(1.0,-1.0)';
    'MDQ'<13>:
      PIN_NUMBER='(V9,0,0,0,0,0)';
      BIDIRECTIONAL='TRUE';
      INPUT_LOAD='(-0.01,0.01)';
      OUTPUT_LOAD='(1.0,-1.0)';
    'MDQ'<12>:
      PIN_NUMBER='(W9,0,0,0,0,0)';
      BIDIRECTIONAL='TRUE';
      INPUT_LOAD='(-0.01,0.01)';
      OUTPUT_LOAD='(1.0,-1.0)';
    'MDQ'<11>:
      PIN_NUMBER='(Y9,0,0,0,0,0)';
      BIDIRECTIONAL='TRUE';
      INPUT_LOAD='(-0.01,0.01)';
      OUTPUT_LOAD='(1.0,-1.0)';
    'MDQ'<10>:
      PIN_NUMBER='(AA9,0,0,0,0,0)';
      BIDIRECTIONAL='TRUE';
      INPUT_LOAD='(-0.01,0.01)';
      OUTPUT_LOAD='(1.0,-1.0)';
    'MDQ'<9>:
      PIN_NUMBER='(AB9,0,0,0,0,0)';
      BIDIRECTIONAL='TRUE';
      INPUT_LOAD='(-0.01,0.01)';
      OUTPUT_LOAD='(1.0,-1.0)';
    'MDQ'<8>:
      PIN_NUMBER='(V10,0,0,0,0,0)';
      BIDIRECTIONAL='TRUE';
      INPUT_LOAD='(-0.01,0.01)';
      OUTPUT_LOAD='(1.0,-1.0)';
    'MDQ'<7>:
      PIN_NUMBER='(Y10,0,0,0,0,0)';
      BIDIRECTIONAL='TRUE';
      INPUT_LOAD='(-0.01,0.01)';
      OUTPUT_LOAD='(1.0,-1.0)';
    'MDQ'<6>:
      PIN_NUMBER='(V11,0,0,0,0,0)';
      BIDIRECTIONAL='TRUE';
      INPUT_LOAD='(-0.01,0.01)';
      OUTPUT_LOAD='(1.0,-1.0)';
    'MDQ'<5>:
      PIN_NUMBER='(W11,0,0,0,0,0)';
      BIDIRECTIONAL='TRUE';
      INPUT_LOAD='(-0.01,0.01)';
      OUTPUT_LOAD='(1.0,-1.0)';
    'MDQ'<4>:
      PIN_NUMBER='(Y11,0,0,0,0,0)';
      BIDIRECTIONAL='TRUE';
      INPUT_LOAD='(-0.01,0.01)';
      OUTPUT_LOAD='(1.0,-1.0)';
    'MDQ'<3>:
      PIN_NUMBER='(AA11,0,0,0,0,0)';
      BIDIRECTIONAL='TRUE';
      INPUT_LOAD='(-0.01,0.01)';
      OUTPUT_LOAD='(1.0,-1.0)';
    'MDQ'<2>:
      PIN_NUMBER='(AB11,0,0,0,0,0)';
      BIDIRECTIONAL='TRUE';
      INPUT_LOAD='(-0.01,0.01)';
      OUTPUT_LOAD='(1.0,-1.0)';
    'MDQ'<1>:
      PIN_NUMBER='(V12,0,0,0,0,0)';
      BIDIRECTIONAL='TRUE';
      INPUT_LOAD='(-0.01,0.01)';
      OUTPUT_LOAD='(1.0,-1.0)';
    'MDQ'<0>:
      PIN_NUMBER='(W12,0,0,0,0,0)';
      BIDIRECTIONAL='TRUE';
      INPUT_LOAD='(-0.01,0.01)';
      OUTPUT_LOAD='(1.0,-1.0)';
    'MDQS0':
      PIN_NUMBER='(AB10,0,0,0,0,0)';
      BIDIRECTIONAL='TRUE';
      INPUT_LOAD='(-0.01,0.01)';
      OUTPUT_LOAD='(1.0,-1.0)';
    'MDQS0_N':
      PIN_NUMBER='(AA10,0,0,0,0,0)';
      BIDIRECTIONAL='TRUE';
      INPUT_LOAD='(-0.01,0.01)';
      OUTPUT_LOAD='(1.0,-1.0)';
    'MDQS1':
      PIN_NUMBER='(AA8,0,0,0,0,0)';
      BIDIRECTIONAL='TRUE';
      INPUT_LOAD='(-0.01,0.01)';
      OUTPUT_LOAD='(1.0,-1.0)';
    'MDQS1_N':
      PIN_NUMBER='(AB8,0,0,0,0,0)';
      BIDIRECTIONAL='TRUE';
      INPUT_LOAD='(-0.01,0.01)';
      OUTPUT_LOAD='(1.0,-1.0)';
    'MIOZ':
      PIN_NUMBER='(V16,0,0,0,0,0)';
      PIN_TYPE='ANALOG';
      NO_LOAD_CHECK='Both';
      NO_IO_CHECK='Both';
      NO_ASSERT_CHECK='TRUE';
      NO_DIR_CHECK='TRUE';
      ALLOW_CONNECT='TRUE';
    'MODT':
      PIN_NUMBER='(V14,0,0,0,0,0)';
      OUTPUT_LOAD='(1.0,-1.0)';
    'MPLLAV33':
      PIN_NUMBER='(0,0,0,0,0,AB19)';
      PINUSE='POWER';
      NO_LOAD_CHECK='Both';
      NO_IO_CHECK='Both';
      NO_ASSERT_CHECK='TRUE';
      NO_DIR_CHECK='TRUE';
      ALLOW_CONNECT='TRUE';
    'MPLLDV12':
      PIN_NUMBER='(0,0,0,0,0,Y18)';
      PINUSE='POWER';
      NO_LOAD_CHECK='Both';
      NO_IO_CHECK='Both';
      NO_ASSERT_CHECK='TRUE';
      NO_DIR_CHECK='TRUE';
      ALLOW_CONNECT='TRUE';
    'MRAS_N':
      PIN_NUMBER='(W13,0,0,0,0,0)';
      OUTPUT_LOAD='(1.0,-1.0)';
    'MVDD'<3>:
      PIN_NUMBER='(0,0,0,0,0,U15)';
      PINUSE='POWER';
      NO_LOAD_CHECK='Both';
      NO_IO_CHECK='Both';
      NO_ASSERT_CHECK='TRUE';
      NO_DIR_CHECK='TRUE';
      ALLOW_CONNECT='TRUE';
    'MVDD'<2>:
      PIN_NUMBER='(0,0,0,0,0,U14)';
      PINUSE='POWER';
      NO_LOAD_CHECK='Both';
      NO_IO_CHECK='Both';
      NO_ASSERT_CHECK='TRUE';
      NO_DIR_CHECK='TRUE';
      ALLOW_CONNECT='TRUE';
    'MVDD'<1>:
      PIN_NUMBER='(0,0,0,0,0,U11)';
      PINUSE='POWER';
      NO_LOAD_CHECK='Both';
      NO_IO_CHECK='Both';
      NO_ASSERT_CHECK='TRUE';
      NO_DIR_CHECK='TRUE';
      ALLOW_CONNECT='TRUE';
    'MVDD'<0>:
      PIN_NUMBER='(0,0,0,0,0,U10)';
      PINUSE='POWER';
      NO_LOAD_CHECK='Both';
      NO_IO_CHECK='Both';
      NO_ASSERT_CHECK='TRUE';
      NO_DIR_CHECK='TRUE';
      ALLOW_CONNECT='TRUE';
    'MVREF':
      PIN_NUMBER='(V13,0,0,0,0,0)';
      INPUT_LOAD='(-0.01,0.01)';
    'MWE_N':
      PIN_NUMBER='(Y13,0,0,0,0,0)';
      OUTPUT_LOAD='(1.0,-1.0)';
    'NC'<1>:
      PIN_NUMBER='(0,0,0,0,0,H22)';
      PINUSE='NC';
      NO_LOAD_CHECK='Both';
      NO_IO_CHECK='Both';
      NO_ASSERT_CHECK='TRUE';
      NO_DIR_CHECK='TRUE';
      ALLOW_CONNECT='TRUE';
    'NC'<0>:
      PIN_NUMBER='(0,0,0,0,0,H21)';
      PINUSE='NC';
      NO_LOAD_CHECK='Both';
      NO_IO_CHECK='Both';
      NO_ASSERT_CHECK='TRUE';
      NO_DIR_CHECK='TRUE';
      ALLOW_CONNECT='TRUE';
    'NC_PEREFCLKN':
      PIN_NUMBER='(0,0,G21,0,0,0)';
      PINUSE='NC';
      NO_LOAD_CHECK='Both';
      NO_IO_CHECK='Both';
      NO_ASSERT_CHECK='TRUE';
      NO_DIR_CHECK='TRUE';
      ALLOW_CONNECT='TRUE';
    'NC_PEREFCLKP':
      PIN_NUMBER='(0,0,G22,0,0,0)';
      PINUSE='NC';
      NO_LOAD_CHECK='Both';
      NO_IO_CHECK='Both';
      NO_ASSERT_CHECK='TRUE';
      NO_DIR_CHECK='TRUE';
      ALLOW_CONNECT='TRUE';
    'NC_PEREXT':
      PIN_NUMBER='(0,0,D20,0,0,0)';
      PINUSE='NC';
      NO_LOAD_CHECK='Both';
      NO_IO_CHECK='Both';
      NO_ASSERT_CHECK='TRUE';
      NO_DIR_CHECK='TRUE';
      ALLOW_CONNECT='TRUE';
    'NC_PERXN':
      PIN_NUMBER='(0,0,F22,0,0,0)';
      PINUSE='NC';
      NO_LOAD_CHECK='Both';
      NO_IO_CHECK='Both';
      NO_ASSERT_CHECK='TRUE';
      NO_DIR_CHECK='TRUE';
      ALLOW_CONNECT='TRUE';
    'NC_PERXP':
      PIN_NUMBER='(0,0,F21,0,0,0)';
      PINUSE='NC';
      NO_LOAD_CHECK='Both';
      NO_IO_CHECK='Both';
      NO_ASSERT_CHECK='TRUE';
      NO_DIR_CHECK='TRUE';
      ALLOW_CONNECT='TRUE';
    'NC_PETXN':
      PIN_NUMBER='(0,0,E21,0,0,0)';
      PINUSE='NC';
      NO_LOAD_CHECK='Both';
      NO_IO_CHECK='Both';
      NO_ASSERT_CHECK='TRUE';
      NO_DIR_CHECK='TRUE';
      ALLOW_CONNECT='TRUE';
    'NC_PETXP':
      PIN_NUMBER='(0,0,E22,0,0,0)';
      PINUSE='NC';
      NO_LOAD_CHECK='Both';
      NO_IO_CHECK='Both';
      NO_ASSERT_CHECK='TRUE';
      NO_DIR_CHECK='TRUE';
      ALLOW_CONNECT='TRUE';
    'NC_PEWAKE_N':
      PIN_NUMBER='(0,0,J22,0,0,0)';
      PINUSE='NC';
      NO_LOAD_CHECK='Both';
      NO_IO_CHECK='Both';
      NO_ASSERT_CHECK='TRUE';
      NO_DIR_CHECK='TRUE';
      ALLOW_CONNECT='TRUE';
    'NTRST':
      PIN_NUMBER='(0,E1,0,0,0,0)';
      BIDIRECTIONAL='TRUE';
      INPUT_LOAD='(-0.01,0.01)';
      OUTPUT_LOAD='(1.0,-1.0)';
    'PEAGND'<1>:
      PIN_NUMBER='(0,0,0,0,0,D22)';
      PINUSE='GROUND';
      NO_LOAD_CHECK='Both';
      NO_IO_CHECK='Both';
      NO_ASSERT_CHECK='TRUE';
      NO_DIR_CHECK='TRUE';
      ALLOW_CONNECT='TRUE';
    'PEAGND'<0>:
      PIN_NUMBER='(0,0,0,0,0,D21)';
      PINUSE='GROUND';
      NO_LOAD_CHECK='Both';
      NO_IO_CHECK='Both';
      NO_ASSERT_CHECK='TRUE';
      NO_DIR_CHECK='TRUE';
      ALLOW_CONNECT='TRUE';
    'PEAV12':
      PIN_NUMBER='(0,0,0,0,0,K17)';
      PINUSE='POWER';
      NO_LOAD_CHECK='Both';
      NO_IO_CHECK='Both';
      NO_ASSERT_CHECK='TRUE';
      NO_DIR_CHECK='TRUE';
      ALLOW_CONNECT='TRUE';
    'PEAV33':
      PIN_NUMBER='(0,0,0,0,0,J17)';
      PINUSE='POWER';
      NO_LOAD_CHECK='Both';
      NO_IO_CHECK='Both';
      NO_ASSERT_CHECK='TRUE';
      NO_DIR_CHECK='TRUE';
      ALLOW_CONNECT='TRUE';
    'PECI':
      PIN_NUMBER='(0,0,AA21,0,0,0)';
      PIN_TYPE='ANALOG';
      NO_LOAD_CHECK='Both';
      NO_IO_CHECK='Both';
      NO_ASSERT_CHECK='TRUE';
      NO_DIR_CHECK='TRUE';
      ALLOW_CONNECT='TRUE';
    'PECIVDD':
      PIN_NUMBER='(0,0,0,0,0,V19)';
      PINUSE='POWER';
      NO_LOAD_CHECK='Both';
      NO_IO_CHECK='Both';
      NO_ASSERT_CHECK='TRUE';
      NO_DIR_CHECK='TRUE';
      ALLOW_CONNECT='TRUE';
    'PERST_N':
      PIN_NUMBER='(0,0,K19,0,0,0)';
      INPUT_LOAD='(-0.01,0.01)';
    'PLLVSS'<2>:
      PIN_NUMBER='(0,0,0,0,0,V18)';
      PINUSE='GROUND';
      NO_LOAD_CHECK='Both';
      NO_IO_CHECK='Both';
      NO_ASSERT_CHECK='TRUE';
      NO_DIR_CHECK='TRUE';
      ALLOW_CONNECT='TRUE';
    'PLLVSS'<1>:
      PIN_NUMBER='(0,0,0,0,0,AA19)';
      PINUSE='GROUND';
      NO_LOAD_CHECK='Both';
      NO_IO_CHECK='Both';
      NO_ASSERT_CHECK='TRUE';
      NO_DIR_CHECK='TRUE';
      ALLOW_CONNECT='TRUE';
    'PLLVSS'<0>:
      PIN_NUMBER='(0,0,0,0,0,AA18)';
      PINUSE='GROUND';
      NO_LOAD_CHECK='Both';
      NO_IO_CHECK='Both';
      NO_ASSERT_CHECK='TRUE';
      NO_DIR_CHECK='TRUE';
      ALLOW_CONNECT='TRUE';
    'PV33D'<10>:
      PIN_NUMBER='(0,0,0,0,0,U9)';
      PINUSE='POWER';
      NO_LOAD_CHECK='Both';
      NO_IO_CHECK='Both';
      NO_ASSERT_CHECK='TRUE';
      NO_DIR_CHECK='TRUE';
      ALLOW_CONNECT='TRUE';
    'PV33D'<9>:
      PIN_NUMBER='(0,0,0,0,0,U8)';
      PINUSE='POWER';
      NO_LOAD_CHECK='Both';
      NO_IO_CHECK='Both';
      NO_ASSERT_CHECK='TRUE';
      NO_DIR_CHECK='TRUE';
      ALLOW_CONNECT='TRUE';
    'PV33D'<8>:
      PIN_NUMBER='(0,0,0,0,0,N17)';
      PINUSE='POWER';
      NO_LOAD_CHECK='Both';
      NO_IO_CHECK='Both';
      NO_ASSERT_CHECK='TRUE';
      NO_DIR_CHECK='TRUE';
      ALLOW_CONNECT='TRUE';
    'PV33D'<7>:
      PIN_NUMBER='(0,0,0,0,0,N6)';
      PINUSE='POWER';
      NO_LOAD_CHECK='Both';
      NO_IO_CHECK='Both';
      NO_ASSERT_CHECK='TRUE';
      NO_DIR_CHECK='TRUE';
      ALLOW_CONNECT='TRUE';
    'PV33D'<6>:
      PIN_NUMBER='(0,0,0,0,0,M17)';
      PINUSE='POWER';
      NO_LOAD_CHECK='Both';
      NO_IO_CHECK='Both';
      NO_ASSERT_CHECK='TRUE';
      NO_DIR_CHECK='TRUE';
      ALLOW_CONNECT='TRUE';
    'PV33D'<5>:
      PIN_NUMBER='(0,0,0,0,0,M6)';
      PINUSE='POWER';
      NO_LOAD_CHECK='Both';
      NO_IO_CHECK='Both';
      NO_ASSERT_CHECK='TRUE';
      NO_DIR_CHECK='TRUE';
      ALLOW_CONNECT='TRUE';
    'PV33D'<4>:
      PIN_NUMBER='(0,0,0,0,0,J6)';
      PINUSE='POWER';
      NO_LOAD_CHECK='Both';
      NO_IO_CHECK='Both';
      NO_ASSERT_CHECK='TRUE';
      NO_DIR_CHECK='TRUE';
      ALLOW_CONNECT='TRUE';
    'PV33D'<3>:
      PIN_NUMBER='(0,0,0,0,0,H17)';
      PINUSE='POWER';
      NO_LOAD_CHECK='Both';
      NO_IO_CHECK='Both';
      NO_ASSERT_CHECK='TRUE';
      NO_DIR_CHECK='TRUE';
      ALLOW_CONNECT='TRUE';
    'PV33D'<2>:
      PIN_NUMBER='(0,0,0,0,0,H6)';
      PINUSE='POWER';
      NO_LOAD_CHECK='Both';
      NO_IO_CHECK='Both';
      NO_ASSERT_CHECK='TRUE';
      NO_DIR_CHECK='TRUE';
      ALLOW_CONNECT='TRUE';
    'PV33D'<1>:
      PIN_NUMBER='(0,0,0,0,0,F13)';
      PINUSE='POWER';
      NO_LOAD_CHECK='Both';
      NO_IO_CHECK='Both';
      NO_ASSERT_CHECK='TRUE';
      NO_DIR_CHECK='TRUE';
      ALLOW_CONNECT='TRUE';
    'PV33D'<0>:
      PIN_NUMBER='(0,0,0,0,0,F12)';
      PINUSE='POWER';
      NO_LOAD_CHECK='Both';
      NO_IO_CHECK='Both';
      NO_ASSERT_CHECK='TRUE';
      NO_DIR_CHECK='TRUE';
      ALLOW_CONNECT='TRUE';
    'R1VDD'<1>:
      PIN_NUMBER='(0,0,0,0,0,F11)';
      PINUSE='POWER';
      NO_LOAD_CHECK='Both';
      NO_IO_CHECK='Both';
      NO_ASSERT_CHECK='TRUE';
      NO_DIR_CHECK='TRUE';
      ALLOW_CONNECT='TRUE';
    'R1VDD'<0>:
      PIN_NUMBER='(0,0,0,0,0,F10)';
      PINUSE='POWER';
      NO_LOAD_CHECK='Both';
      NO_IO_CHECK='Both';
      NO_ASSERT_CHECK='TRUE';
      NO_DIR_CHECK='TRUE';
      ALLOW_CONNECT='TRUE';
    'R2VDD'<1>:
      PIN_NUMBER='(0,0,0,0,0,F9)';
      PINUSE='POWER';
      NO_LOAD_CHECK='Both';
      NO_IO_CHECK='Both';
      NO_ASSERT_CHECK='TRUE';
      NO_DIR_CHECK='TRUE';
      ALLOW_CONNECT='TRUE';
    'R2VDD'<0>:
      PIN_NUMBER='(0,0,0,0,0,F8)';
      PINUSE='POWER';
      NO_LOAD_CHECK='Both';
      NO_IO_CHECK='Both';
      NO_ASSERT_CHECK='TRUE';
      NO_DIR_CHECK='TRUE';
      ALLOW_CONNECT='TRUE';
    'RGMII1RXCK_RMII1RCLK_GPIOU4':
      PIN_NUMBER='(0,0,0,0,E11,0)';
      INPUT_LOAD='(-0.01,0.01)';
    'RGMII1RXCTL_GPIOU5':
      PIN_NUMBER='(0,0,0,0,D11,0)';
      INPUT_LOAD='(-0.01,0.01)';
    'RGMII1RXD0_RMII1RXD0_GPIOU6':
      PIN_NUMBER='(0,0,0,0,C11,0)';
      INPUT_LOAD='(-0.01,0.01)';
    'RGMII1RXD1_RMII1RXD1_GPIOU7':
      PIN_NUMBER='(0,0,0,0,B11,0)';
      INPUT_LOAD='(-0.01,0.01)';
    'RGMII1RXD2_RMII1CRSDV_GPIOV0':
      PIN_NUMBER='(0,0,0,0,A11,0)';
      INPUT_LOAD='(-0.01,0.01)';
    'RGMII1RXD3_RMII1RXER_GPIOV1':
      PIN_NUMBER='(0,0,0,0,E10,0)';
      INPUT_LOAD='(-0.01,0.01)';
    'RGMII1TXCK_RMII1TXEN_GPIOT0':
      PIN_NUMBER='(0,0,0,0,A12,0)';
      OUTPUT_LOAD='(1.0,-1.0)';
    'RGMII1TXCTL_GPIOT1':
      PIN_NUMBER='(0,0,0,0,B12,0)';
      OUTPUT_LOAD='(1.0,-1.0)';
    'RGMII1TXD0_RMII1TXD0_GPIOT2':
      PIN_NUMBER='(0,0,0,0,C12,0)';
      OUTPUT_LOAD='(1.0,-1.0)';
    'RGMII1TXD1_RMII1TXD1_GPIOT3':
      PIN_NUMBER='(0,0,0,0,D12,0)';
      OUTPUT_LOAD='(1.0,-1.0)';
    'RGMII1TXD2_GPIOT4':
      PIN_NUMBER='(0,0,0,0,E12,0)';
      OUTPUT_LOAD='(1.0,-1.0)';
    'RGMII1TXD3_GPIOT5':
      PIN_NUMBER='(0,0,0,0,A13,0)';
      OUTPUT_LOAD='(1.0,-1.0)';
    'RGMII2RXCK_RMII2RCLK_GPIOV2':
      PIN_NUMBER='(0,0,0,0,C9,0)';
      INPUT_LOAD='(-0.01,0.01)';
    'RGMII2RXCTL_GPIOV3':
      PIN_NUMBER='(0,0,0,0,B9,0)';
      INPUT_LOAD='(-0.01,0.01)';
    'RGMII2RXD0_RMII2RXD0_GPIOV4':
      PIN_NUMBER='(0,0,0,0,A9,0)';
      INPUT_LOAD='(-0.01,0.01)';
    'RGMII2RXD1_RMII2RXD1_GPIOV5':
      PIN_NUMBER='(0,0,0,0,E8,0)';
      INPUT_LOAD='(-0.01,0.01)';
    'RGMII2RXD2_RMII2CRSDV_GPIOV6':
      PIN_NUMBER='(0,0,0,0,D8,0)';
      INPUT_LOAD='(-0.01,0.01)';
    'RGMII2RXD3_RMII2RXER_GPIOV7':
      PIN_NUMBER='(0,0,0,0,C8,0)';
      INPUT_LOAD='(-0.01,0.01)';
    'RGMII2TXCK_RMII2TXEN_GPIOT6':
      PIN_NUMBER='(0,0,0,0,D9,0)';
      OUTPUT_LOAD='(1.0,-1.0)';
    'RGMII2TXCTL_GPIOT7':
      PIN_NUMBER='(0,0,0,0,E9,0)';
      OUTPUT_LOAD='(1.0,-1.0)';
    'RGMII2TXD0_RMII2TXD0_GPIOU0':
      PIN_NUMBER='(0,0,0,0,A10,0)';
      OUTPUT_LOAD='(1.0,-1.0)';
    'RGMII2TXD1_RMII2TXD1_GPIOU1':
      PIN_NUMBER='(0,0,0,0,B10,0)';
      OUTPUT_LOAD='(1.0,-1.0)';
    'RGMII2TXD2_GPIOU2':
      PIN_NUMBER='(0,0,0,0,C10,0)';
      OUTPUT_LOAD='(1.0,-1.0)';
    'RGMII2TXD3_GPIOU3':
      PIN_NUMBER='(0,0,0,0,D10,0)';
      OUTPUT_LOAD='(1.0,-1.0)';
    'RGMIICK':
      PIN_NUMBER='(0,0,0,0,B8,0)';
      INPUT_LOAD='(-0.01,0.01)';
    'ROMA'<1>:
      PIN_NUMBER='(0,0,0,R21,0,0)';
      BIDIRECTIONAL='TRUE';
      INPUT_LOAD='(-0.01,0.01)';
      OUTPUT_LOAD='(1.0,-1.0)';
    'ROMA'<0>:
      PIN_NUMBER='(0,0,0,R20,0,0)';
      BIDIRECTIONAL='TRUE';
      INPUT_LOAD='(-0.01,0.01)';
      OUTPUT_LOAD='(1.0,-1.0)';
    'ROMA10_GPIOAA0_VPOG0':
      PIN_NUMBER='(0,0,0,M21,0,0)';
      BIDIRECTIONAL='TRUE';
      INPUT_LOAD='(-0.01,0.01)';
      OUTPUT_LOAD='(1.0,-1.0)';
    'ROMA11_GPIOAA1_VPOG1':
      PIN_NUMBER='(0,0,0,M22,0,0)';
      BIDIRECTIONAL='TRUE';
      INPUT_LOAD='(-0.01,0.01)';
      OUTPUT_LOAD='(1.0,-1.0)';
    'ROMA12_GPIOAA2_VPOG2':
      PIN_NUMBER='(0,0,0,L18,0,0)';
      BIDIRECTIONAL='TRUE';
      INPUT_LOAD='(-0.01,0.01)';
      OUTPUT_LOAD='(1.0,-1.0)';
    'ROMA13_GPIOAA3_VPOG3':
      PIN_NUMBER='(0,0,0,L19,0,0)';
      BIDIRECTIONAL='TRUE';
      INPUT_LOAD='(-0.01,0.01)';
      OUTPUT_LOAD='(1.0,-1.0)';
    'ROMA14_GPIOAA4_VPOG4':
      PIN_NUMBER='(0,0,0,L20,0,0)';
      BIDIRECTIONAL='TRUE';
      INPUT_LOAD='(-0.01,0.01)';
      OUTPUT_LOAD='(1.0,-1.0)';
    'ROMA15_GPIOAA5_VPOG5':
      PIN_NUMBER='(0,0,0,L21,0,0)';
      BIDIRECTIONAL='TRUE';
      INPUT_LOAD='(-0.01,0.01)';
      OUTPUT_LOAD='(1.0,-1.0)';
    'ROMA16_GPIOAA6_VPOG6':
      PIN_NUMBER='(0,0,0,T18,0,0)';
      BIDIRECTIONAL='TRUE';
      INPUT_LOAD='(-0.01,0.01)';
      OUTPUT_LOAD='(1.0,-1.0)';
    'ROMA17_GPIOAA7_VPOG7':
      PIN_NUMBER='(0,0,0,N18,0,0)';
      BIDIRECTIONAL='TRUE';
      INPUT_LOAD='(-0.01,0.01)';
      OUTPUT_LOAD='(1.0,-1.0)';
    'ROMA18_GPIOAB0_VPOR0':
      PIN_NUMBER='(0,0,0,N19,0,0)';
      BIDIRECTIONAL='TRUE';
      INPUT_LOAD='(-0.01,0.01)';
      OUTPUT_LOAD='(1.0,-1.0)';
    'ROMA19_GPIOAB1_VPOR1':
      PIN_NUMBER='(0,0,0,M18,0,0)';
      BIDIRECTIONAL='TRUE';
      INPUT_LOAD='(-0.01,0.01)';
      OUTPUT_LOAD='(1.0,-1.0)';
    'ROMA20_GPIOAB2_VPOR2':
      PIN_NUMBER='(0,0,0,N22,0,0)';
      BIDIRECTIONAL='TRUE';
      INPUT_LOAD='(-0.01,0.01)';
      OUTPUT_LOAD='(1.0,-1.0)';
    'ROMA21_GPIOAB3_VPOR3':
      PIN_NUMBER='(0,0,0,N20,0,0)';
      BIDIRECTIONAL='TRUE';
      INPUT_LOAD='(-0.01,0.01)';
      OUTPUT_LOAD='(1.0,-1.0)';
    'ROMA22_GPIOS6_VPOR4':
      PIN_NUMBER='(0,0,0,L22,0,0)';
      BIDIRECTIONAL='TRUE';
      INPUT_LOAD='(-0.01,0.01)';
      OUTPUT_LOAD='(1.0,-1.0)';
    'ROMA23_GPIOS7_VPOR5':
      PIN_NUMBER='(0,0,0,K18,0,0)';
      BIDIRECTIONAL='TRUE';
      INPUT_LOAD='(-0.01,0.01)';
      OUTPUT_LOAD='(1.0,-1.0)';
    'ROMA2_GPIOZ0_VPOB0':
      PIN_NUMBER='(0,0,0,R22,0,0)';
      BIDIRECTIONAL='TRUE';
      INPUT_LOAD='(-0.01,0.01)';
      OUTPUT_LOAD='(1.0,-1.0)';
    'ROMA3_GPIOZ1_VPOB1':
      PIN_NUMBER='(0,0,0,P18,0,0)';
      BIDIRECTIONAL='TRUE';
      INPUT_LOAD='(-0.01,0.01)';
      OUTPUT_LOAD='(1.0,-1.0)';
    'ROMA4_GPIOZ2_VPOB2':
      PIN_NUMBER='(0,0,0,P19,0,0)';
      BIDIRECTIONAL='TRUE';
      INPUT_LOAD='(-0.01,0.01)';
      OUTPUT_LOAD='(1.0,-1.0)';
    'ROMA5_GPIOZ3_VPOB3':
      PIN_NUMBER='(0,0,0,P20,0,0)';
      BIDIRECTIONAL='TRUE';
      INPUT_LOAD='(-0.01,0.01)';
      OUTPUT_LOAD='(1.0,-1.0)';
    'ROMA6_GPIOZ4_VPOB4':
      PIN_NUMBER='(0,0,0,P21,0,0)';
      BIDIRECTIONAL='TRUE';
      INPUT_LOAD='(-0.01,0.01)';
      OUTPUT_LOAD='(1.0,-1.0)';
    'ROMA7_GPIOZ5_VPOB5':
      PIN_NUMBER='(0,0,0,P22,0,0)';
      BIDIRECTIONAL='TRUE';
      INPUT_LOAD='(-0.01,0.01)';
      OUTPUT_LOAD='(1.0,-1.0)';
    'ROMA8_GPIOZ6_VPOB6':
      PIN_NUMBER='(0,0,0,M19,0,0)';
      BIDIRECTIONAL='TRUE';
      INPUT_LOAD='(-0.01,0.01)';
      OUTPUT_LOAD='(1.0,-1.0)';
    'ROMA9_GPIOZ7_VPOB7':
      PIN_NUMBER='(0,0,0,M20,0,0)';
      BIDIRECTIONAL='TRUE';
      INPUT_LOAD='(-0.01,0.01)';
      OUTPUT_LOAD='(1.0,-1.0)';
    'ROMCS0_N':
      PIN_NUMBER='(0,0,0,R19,0,0)';
      BIDIRECTIONAL='TRUE';
      INPUT_LOAD='(-0.01,0.01)';
      OUTPUT_LOAD='(1.0,-1.0)';
    'ROMD0':
      PIN_NUMBER='(0,0,0,T22,0,0)';
      BIDIRECTIONAL='TRUE';
      INPUT_LOAD='(-0.01,0.01)';
      OUTPUT_LOAD='(1.0,-1.0)';
    'ROMD1':
      PIN_NUMBER='(0,0,0,T21,0,0)';
      BIDIRECTIONAL='TRUE';
      INPUT_LOAD='(-0.01,0.01)';
      OUTPUT_LOAD='(1.0,-1.0)';
    'ROMD2':
      PIN_NUMBER='(0,0,0,T20,0,0)';
      BIDIRECTIONAL='TRUE';
      INPUT_LOAD='(-0.01,0.01)';
      OUTPUT_LOAD='(1.0,-1.0)';
    'ROMD3':
      PIN_NUMBER='(0,0,0,U22,0,0)';
      BIDIRECTIONAL='TRUE';
      INPUT_LOAD='(-0.01,0.01)';
      OUTPUT_LOAD='(1.0,-1.0)';
    'ROMD4_GPIOS0_VPODE':
      PIN_NUMBER='(0,0,0,U21,0,0)';
      BIDIRECTIONAL='TRUE';
      INPUT_LOAD='(-0.01,0.01)';
      OUTPUT_LOAD='(1.0,-1.0)';
    'ROMD5_GPIOS1_VPOHS':
      PIN_NUMBER='(0,0,0,T19,0,0)';
      BIDIRECTIONAL='TRUE';
      INPUT_LOAD='(-0.01,0.01)';
      OUTPUT_LOAD='(1.0,-1.0)';
    'ROMD6_GPIOS2_VPOVS':
      PIN_NUMBER='(0,0,0,V22,0,0)';
      BIDIRECTIONAL='TRUE';
      INPUT_LOAD='(-0.01,0.01)';
      OUTPUT_LOAD='(1.0,-1.0)';
    'ROMD7_GPIOS3_VPOCLK':
      PIN_NUMBER='(0,0,0,U20,0,0)';
      BIDIRECTIONAL='TRUE';
      INPUT_LOAD='(-0.01,0.01)';
      OUTPUT_LOAD='(1.0,-1.0)';
    'ROMOE_N_GPIOS4':
      PIN_NUMBER='(0,0,0,R18,0,0)';
      BIDIRECTIONAL='TRUE';
      INPUT_LOAD='(-0.01,0.01)';
      OUTPUT_LOAD='(1.0,-1.0)';
    'ROMWE_N_GPIOS5':
      PIN_NUMBER='(0,0,0,N21,0,0)';
      BIDIRECTIONAL='TRUE';
      INPUT_LOAD='(-0.01,0.01)';
      OUTPUT_LOAD='(1.0,-1.0)';
    'RTCK':
      PIN_NUMBER='(0,G4,0,0,0,0)';
      OUTPUT_LOAD='(1.0,-1.0)';
    'RXD5':
      PIN_NUMBER='(0,0,G1,0,0,0)';
      INPUT_LOAD='(-0.01,0.01)';
    'SCL'<2>:
      PIN_NUMBER='(0,J19,0,0,0,0)';
      BIDIRECTIONAL='TRUE';
      INPUT_LOAD='(-0.01,0.01)';
      OUTPUT_LOAD='(1.0,-1.0)';
    'SCL'<1>:
      PIN_NUMBER='(0,K21,0,0,0,0)';
      BIDIRECTIONAL='TRUE';
      INPUT_LOAD='(-0.01,0.01)';
      OUTPUT_LOAD='(1.0,-1.0)';
    'SDA'<2>:
      PIN_NUMBER='(0,J18,0,0,0,0)';
      BIDIRECTIONAL='TRUE';
      INPUT_LOAD='(-0.01,0.01)';
      OUTPUT_LOAD='(1.0,-1.0)';
    'SDA'<1>:
      PIN_NUMBER='(0,K22,0,0,0,0)';
      BIDIRECTIONAL='TRUE';
      INPUT_LOAD='(-0.01,0.01)';
      OUTPUT_LOAD='(1.0,-1.0)';
    'SRST_N':
      PIN_NUMBER='(0,0,W20,0,0,0)';
      INPUT_LOAD='(-0.01,0.01)';
    'TCK':
      PIN_NUMBER='(0,F2,0,0,0,0)';
      BIDIRECTIONAL='TRUE';
      INPUT_LOAD='(-0.01,0.01)';
      OUTPUT_LOAD='(1.0,-1.0)';
    'TDI':
      PIN_NUMBER='(0,F1,0,0,0,0)';
      BIDIRECTIONAL='TRUE';
      INPUT_LOAD='(-0.01,0.01)';
      OUTPUT_LOAD='(1.0,-1.0)';
    'TDO':
      PIN_NUMBER='(0,G3,0,0,0,0)';
      BIDIRECTIONAL='TRUE';
      INPUT_LOAD='(-0.01,0.01)';
      OUTPUT_LOAD='(1.0,-1.0)';
    'TMS':
      PIN_NUMBER='(0,G2,0,0,0,0)';
      BIDIRECTIONAL='TRUE';
      INPUT_LOAD='(-0.01,0.01)';
      OUTPUT_LOAD='(1.0,-1.0)';
    'TXD5':
      PIN_NUMBER='(0,0,H5,0,0,0)';
      OUTPUT_LOAD='(1.0,-1.0)';
    'USB11_HDN':
      PIN_NUMBER='(0,J2,0,0,0,0)';
      BIDIRECTIONAL='TRUE';
      INPUT_LOAD='(-0.01,0.01)';
      OUTPUT_LOAD='(1.0,-1.0)';
    'USB11_HDP':
      PIN_NUMBER='(0,J1,0,0,0,0)';
      BIDIRECTIONAL='TRUE';
      INPUT_LOAD='(-0.01,0.01)';
      OUTPUT_LOAD='(1.0,-1.0)';
    'USB2AV33':
      PIN_NUMBER='(0,0,0,0,0,W18)';
      PINUSE='POWER';
      NO_LOAD_CHECK='Both';
      NO_IO_CHECK='Both';
      NO_ASSERT_CHECK='TRUE';
      NO_DIR_CHECK='TRUE';
      ALLOW_CONNECT='TRUE';
    'USB2AVSS':
      PIN_NUMBER='(0,0,0,0,0,Y19)';
      PINUSE='GROUND';
      NO_LOAD_CHECK='Both';
      NO_IO_CHECK='Both';
      NO_ASSERT_CHECK='TRUE';
      NO_DIR_CHECK='TRUE';
      ALLOW_CONNECT='TRUE';
    'USB2VRES':
      PIN_NUMBER='(0,AA20,0,0,0,0)';
      PIN_TYPE='ANALOG';
      NO_LOAD_CHECK='Both';
      NO_IO_CHECK='Both';
      NO_ASSERT_CHECK='TRUE';
      NO_DIR_CHECK='TRUE';
      ALLOW_CONNECT='TRUE';
    'V1PLLAV12':
      PIN_NUMBER='(0,0,0,0,0,W19)';
      PINUSE='POWER';
      NO_LOAD_CHECK='Both';
      NO_IO_CHECK='Both';
      NO_ASSERT_CHECK='TRUE';
      NO_DIR_CHECK='TRUE';
      ALLOW_CONNECT='TRUE';
    'V2PLLAV12':
      PIN_NUMBER='(0,0,0,0,0,Y20)';
      PINUSE='POWER';
      NO_LOAD_CHECK='Both';
      NO_IO_CHECK='Both';
      NO_ASSERT_CHECK='TRUE';
      NO_DIR_CHECK='TRUE';
      ALLOW_CONNECT='TRUE';
    'VGAHS_GPIOJ4':
      PIN_NUMBER='(0,T4,0,0,0,0)';
      OUTPUT_LOAD='(1.0,-1.0)';
    'VGAVS_GPIOJ5':
      PIN_NUMBER='(0,U2,0,0,0,0)';
      OUTPUT_LOAD='(1.0,-1.0)';
  end_pin;
  body
    PART_NAME='AST1250';
    PHYS_DES_PREFIX='U';
  end_body;
end_primitive;

END.
